G04 ================== begin FILE IDENTIFICATION RECORD ==================*
G04 Layout Name:  9054_F0T_PDB_BD_GPU_F_V04_1213_1550.brd*
G04 Film Name:    gnd1*
G04 File Format:  Gerber RS274X*
G04 File Origin:  Cadence Allegro 17.2-S081*
G04 Origin Date:  Wed Dec 28 10:19:02 2022*
G04 *
G04 Layer:  DRAWING FORMAT/TITLE_BLOCK_A*
G04 Layer:  PIN/SPECIAL_DRILL*
G04 Layer:  VIA CLASS/GND1*
G04 Layer:  PIN/GND1*
G04 Layer:  MANUFACTURING/PHOTOPLOT_OUTLINE*
G04 Layer:  ETCH/GND1*
G04 Layer:  DRAWING FORMAT/TITLE_BLOCK*
G04 Layer:  DRAWING FORMAT/TITLE_DATA_GND1*
G04 *
G04 Offset:    (0.00 0.00)*
G04 Mirror:    No*
G04 Mode:      Negative*
G04 Rotation:  0*
G04 FullContactRelief:  No*
G04 UndefLineWidth:     6.00*
G04 ================== end FILE IDENTIFICATION RECORD ====================*
%FSLAX25Y25*MOIN*%
%IR0*IPPOS*OFA0.00000B0.00000*MIA0B0*SFA1.00000B1.00000*%
%ADD17C,.03*%
%ADD47C,.061*%
%ADD20C,.07*%
%ADD42C,.026*%
%ADD19C,.07*%
%AMMACRO15*
4,1,36,0.0,.01,
-.001736,.009848,
-.00342,.009397,
-.005,.00866,
-.006428,.00766,
-.00766,.006428,
-.00866,.005,
-.009397,.00342,
-.009848,.001736,
-.01,0.0,
-.009848,-.001736,
-.009397,-.00342,
-.00866,-.005,
-.00766,-.006428,
-.006428,-.00766,
-.005,-.00866,
-.00342,-.009397,
-.001736,-.009848,
0.0,-.01,
.001736,-.009848,
.00342,-.009397,
.005,-.00866,
.006428,-.00766,
.00766,-.006428,
.00866,-.005,
.009397,-.00342,
.009848,-.001736,
.01,0.0,
.009848,.001736,
.009397,.00342,
.00866,.005,
.00766,.006428,
.006428,.00766,
.005,.00866,
.00342,.009397,
.001736,.009848,
0.0,.01,
0.0*
%
%ADD15MACRO15*%
%AMMACRO29*
4,1,36,.0025,0.0,
.002462,.000434,
.002349,.000855,
.002165,.00125,
.001915,.001607,
.001607,.001915,
.00125,.002165,
.000855,.002349,
.000434,.002462,
0.0,.0025,
-.000434,.002462,
-.000855,.002349,
-.00125,.002165,
-.001607,.001915,
-.001915,.001607,
-.002165,.00125,
-.002349,.000855,
-.002462,.000434,
-.0025,0.0,
-.002462,-.000434,
-.002349,-.000855,
-.002165,-.00125,
-.001915,-.001607,
-.001607,-.001915,
-.00125,-.002165,
-.000855,-.002349,
-.000434,-.002462,
0.0,-.0025,
.000434,-.002462,
.000855,-.002349,
.00125,-.002165,
.001607,-.001915,
.001915,-.001607,
.002165,-.00125,
.002349,-.000855,
.002462,-.000434,
.0025,0.0,
270.*
%
%ADD29MACRO29*%
%AMMACRO28*
4,1,36,.0025,0.0,
.002462,.000434,
.002349,.000855,
.002165,.00125,
.001915,.001607,
.001607,.001915,
.00125,.002165,
.000855,.002349,
.000434,.002462,
0.0,.0025,
-.000434,.002462,
-.000855,.002349,
-.00125,.002165,
-.001607,.001915,
-.001915,.001607,
-.002165,.00125,
-.002349,.000855,
-.002462,.000434,
-.0025,0.0,
-.002462,-.000434,
-.002349,-.000855,
-.002165,-.00125,
-.001915,-.001607,
-.001607,-.001915,
-.00125,-.002165,
-.000855,-.002349,
-.000434,-.002462,
0.0,-.0025,
.000434,-.002462,
.000855,-.002349,
.00125,-.002165,
.001607,-.001915,
.001915,-.001607,
.002165,-.00125,
.002349,-.000855,
.002462,-.000434,
.0025,0.0,
180.*
%
%ADD28MACRO28*%
%ADD37C,.066*%
%ADD34C,.06015*%
%ADD31C,.087*%
%AMMACRO21*
4,1,36,0.0,.0135,
-.002344,.013295,
-.004617,.012686,
-.00675,.011691,
-.008678,.010342,
-.010342,.008678,
-.011691,.00675,
-.012686,.004617,
-.013295,.002344,
-.0135,0.0,
-.013295,-.002344,
-.012686,-.004617,
-.011691,-.00675,
-.010342,-.008678,
-.008678,-.010342,
-.00675,-.011691,
-.004617,-.012686,
-.002344,-.013295,
0.0,-.0135,
.002344,-.013295,
.004617,-.012686,
.00675,-.011691,
.008678,-.010342,
.010342,-.008678,
.011691,-.00675,
.012686,-.004617,
.013295,-.002344,
.0135,0.0,
.013295,.002344,
.012686,.004617,
.011691,.00675,
.010342,.008678,
.008678,.010342,
.00675,.011691,
.004617,.012686,
.002344,.013295,
0.0,.0135,
0.0*
%
%ADD21MACRO21*%
%AMMACRO43*
4,1,17,.09027,.06198,
.099661,.045363,
.106024,.027368,
.109166,.008541,
.108991,-.010545,
.105504,-.029311,
.098811,-.047186,
.09027,-.06198,
.0953,-.06701,
.105488,-.049443,
.112471,-.030374,
.116037,-.010382,
.116077,.009925,
.11259,.029931,
.105682,.049027,
.095563,.066634,
.0953,.06701,
.09027,.06198,
90.*
4,1,17,.06198,-.09027,
.045363,-.099661,
.027368,-.106024,
.008541,-.109166,
-.010545,-.108991,
-.029311,-.105504,
-.047186,-.098811,
-.06198,-.09027,
-.06701,-.0953,
-.049443,-.105488,
-.030374,-.112471,
-.010382,-.116037,
.009925,-.116077,
.029931,-.11259,
.049027,-.105682,
.066634,-.095563,
.06701,-.0953,
.06198,-.09027,
90.*
4,1,17,-.09027,-.06198,
-.099661,-.045363,
-.106024,-.027368,
-.109166,-.008541,
-.108991,.010545,
-.105504,.029311,
-.098811,.047186,
-.09027,.06198,
-.0953,.06701,
-.105488,.049443,
-.112471,.030374,
-.116037,.010382,
-.116077,-.009925,
-.11259,-.029931,
-.105682,-.049027,
-.095563,-.066634,
-.0953,-.06701,
-.09027,-.06198,
90.*
4,1,17,-.06198,.09027,
-.045363,.099661,
-.027368,.106024,
-.008541,.109166,
.010545,.108991,
.029311,.105504,
.047186,.098811,
.06198,.09027,
.06701,.0953,
.049443,.105488,
.030374,.112471,
.010382,.116037,
-.009925,.116077,
-.029931,.11259,
-.049027,.105682,
-.066634,.095563,
-.06701,.0953,
-.06198,.09027,
90.*
%
%ADD43MACRO43*%
%ADD18C,.04952*%
%AMMACRO45*
4,1,15,.02475,.01414,
.026829,.009627,
.028094,.004822,
.028504,-.000129,
.028049,-.005077,
.026741,-.009871,
.02475,-.01414,
.02984,-.01923,
.032726,-.013756,
.034617,-.007864,
.035457,-.001734,
.03522,.00445,
.033912,.010498,
.031574,.016227,
.02984,.01923,
.02475,.01414,
90.*
4,1,15,.01414,-.02475,
.009627,-.026829,
.004822,-.028094,
-.000129,-.028504,
-.005077,-.028049,
-.009871,-.026741,
-.01414,-.02475,
-.01923,-.02984,
-.013756,-.032726,
-.007864,-.034617,
-.001734,-.035457,
.00445,-.03522,
.010498,-.033912,
.016227,-.031574,
.01923,-.02984,
.01414,-.02475,
90.*
4,1,15,-.02475,-.01414,
-.026829,-.009627,
-.028094,-.004822,
-.028504,.000129,
-.028049,.005077,
-.026741,.009871,
-.02475,.01414,
-.02984,.01923,
-.032726,.013756,
-.034617,.007864,
-.035457,.001734,
-.03522,-.00445,
-.033912,-.010498,
-.031574,-.016227,
-.02984,-.01923,
-.02475,-.01414,
90.*
4,1,15,-.01414,.02475,
-.009627,.026829,
-.004822,.028094,
.000129,.028504,
.005077,.028049,
.009871,.026741,
.01414,.02475,
.01923,.02984,
.013756,.032726,
.007864,.034617,
.001734,.035457,
-.00445,.03522,
-.010498,.033912,
-.016227,.031574,
-.01923,.02984,
-.01414,.02475,
90.*
%
%ADD45MACRO45*%
%AMMACRO38*
4,1,16,.02657,.01597,
.02894,.011114,
.03043,.005919,
.030995,.000545,
.030619,-.004845,
.029313,-.010088,
.027115,-.015025,
.02657,-.01597,
.03164,-.02104,
.034813,-.015226,
.036928,-.00895,
.037921,-.002401,
.037762,.00422,
.036455,.010713,
.034041,.016881,
.03164,.02104,
.02657,.01597,
90.*
4,1,16,.01597,-.02657,
.011114,-.02894,
.005919,-.03043,
.000545,-.030995,
-.004845,-.030619,
-.010088,-.029313,
-.015025,-.027115,
-.01597,-.02657,
-.02104,-.03164,
-.015226,-.034813,
-.00895,-.036928,
-.002401,-.037921,
.00422,-.037762,
.010713,-.036455,
.016881,-.034041,
.02104,-.03164,
.01597,-.02657,
90.*
4,1,16,-.02657,-.01597,
-.02894,-.011114,
-.03043,-.005919,
-.030995,-.000545,
-.030619,.004845,
-.029313,.010088,
-.027115,.015025,
-.02657,.01597,
-.03164,.02104,
-.034813,.015226,
-.036928,.00895,
-.037921,.002401,
-.037762,-.00422,
-.036455,-.010713,
-.034041,-.016881,
-.03164,-.02104,
-.02657,-.01597,
90.*
4,1,16,-.01597,.02657,
-.011114,.02894,
-.005919,.03043,
-.000545,.030995,
.004845,.030619,
.010088,.029313,
.015025,.027115,
.01597,.02657,
.02104,.03164,
.015226,.034813,
.00895,.036928,
.002401,.037921,
-.00422,.037762,
-.010713,.036455,
-.016881,.034041,
-.02104,.03164,
-.01597,.02657,
90.*
%
%ADD38MACRO38*%
%AMMACRO41*
4,1,15,.03682,.01914,
.039584,.012455,
.041146,.005393,
.041457,-.001834,
.040509,-.009005,
.03833,-.015903,
.03682,-.01914,
.04197,-.0243,
.045552,-.016643,
.04775,-.00848,
.048497,-.000059,
.047771,.008363,
.045593,.016531,
.042029,.024197,
.04197,.0243,
.03682,.01914,
90.*
4,1,15,.01914,-.03682,
.012455,-.039584,
.005393,-.041146,
-.001834,-.041457,
-.009005,-.040509,
-.015903,-.03833,
-.01914,-.03682,
-.0243,-.04197,
-.016643,-.045552,
-.00848,-.04775,
-.000059,-.048497,
.008363,-.047771,
.016531,-.045593,
.024197,-.042029,
.0243,-.04197,
.01914,-.03682,
90.*
4,1,15,-.03682,-.01914,
-.039584,-.012455,
-.041146,-.005393,
-.041457,.001834,
-.040509,.009005,
-.03833,.015903,
-.03682,.01914,
-.04197,.0243,
-.045552,.016643,
-.04775,.00848,
-.048497,.000059,
-.047771,-.008363,
-.045593,-.016531,
-.042029,-.024197,
-.04197,-.0243,
-.03682,-.01914,
90.*
4,1,15,-.01914,.03682,
-.012455,.039584,
-.005393,.041146,
.001834,.041457,
.009005,.040509,
.015903,.03833,
.01914,.03682,
.0243,.04197,
.016643,.045552,
.00848,.04775,
.000059,.048497,
-.008363,.047771,
-.016531,.045593,
-.024197,.042029,
-.0243,.04197,
-.01914,.03682,
90.*
%
%ADD41MACRO41*%
%AMMACRO40*
4,1,15,-.03682,.01914,
-.039584,.012455,
-.041146,.005393,
-.041457,-.001834,
-.040509,-.009005,
-.03833,-.015903,
-.03682,-.01914,
-.04197,-.0243,
-.045552,-.016643,
-.04775,-.00848,
-.048497,-.000059,
-.047771,.008363,
-.045593,.016531,
-.042029,.024197,
-.04197,.0243,
-.03682,.01914,
90.*
4,1,15,-.01914,-.03682,
-.012455,-.039584,
-.005393,-.041146,
.001834,-.041457,
.009005,-.040509,
.015903,-.03833,
.01914,-.03682,
.0243,-.04197,
.016643,-.045552,
.00848,-.04775,
.000059,-.048497,
-.008363,-.047771,
-.016531,-.045593,
-.024197,-.042029,
-.0243,-.04197,
-.01914,-.03682,
90.*
4,1,15,.03682,-.01914,
.039584,-.012455,
.041146,-.005393,
.041457,.001834,
.040509,.009005,
.03833,.015903,
.03682,.01914,
.04197,.0243,
.045552,.016643,
.04775,.00848,
.048497,.000059,
.047771,-.008363,
.045593,-.016531,
.042029,-.024197,
.04197,-.0243,
.03682,-.01914,
90.*
4,1,15,.01914,.03682,
.012455,.039584,
.005393,.041146,
-.001834,.041457,
-.009005,.040509,
-.015903,.03833,
-.01914,.03682,
-.0243,.04197,
-.016643,.045552,
-.00848,.04775,
-.000059,.048497,
.008363,.047771,
.016531,.045593,
.024197,.042029,
.0243,.04197,
.01914,.03682,
90.*
%
%ADD40MACRO40*%
%ADD25C,.113*%
%AMMACRO14*
4,1,36,0.0,.005,
.000868,.004924,
.00171,.004698,
.0025,.00433,
.003214,.00383,
.00383,.003214,
.00433,.0025,
.004698,.00171,
.004924,.000868,
.005,0.0,
.004924,-.000868,
.004698,-.00171,
.00433,-.0025,
.00383,-.003214,
.003214,-.00383,
.0025,-.00433,
.00171,-.004698,
.000868,-.004924,
0.0,-.005,
-.000868,-.004924,
-.00171,-.004698,
-.0025,-.00433,
-.003214,-.00383,
-.00383,-.003214,
-.00433,-.0025,
-.004698,-.00171,
-.004924,-.000868,
-.005,0.0,
-.004924,.000868,
-.004698,.00171,
-.00433,.0025,
-.00383,.003214,
-.003214,.00383,
-.0025,.00433,
-.00171,.004698,
-.000868,.004924,
0.0,.005,
180.*
%
%ADD14MACRO14*%
%ADD27C,.115*%
%ADD46C,.116*%
%ADD10C,.125*%
%ADD23C,.155*%
%ADD35C,.256*%
%AMMACRO26*
4,1,36,0.0,.0135,
-.002344,.013295,
-.004617,.012686,
-.00675,.011691,
-.008678,.010342,
-.010342,.008678,
-.011691,.00675,
-.012686,.004617,
-.013295,.002344,
-.0135,0.0,
-.013295,-.002344,
-.012686,-.004617,
-.011691,-.00675,
-.010342,-.008678,
-.008678,-.010342,
-.00675,-.011691,
-.004617,-.012686,
-.002344,-.013295,
0.0,-.0135,
.002344,-.013295,
.004617,-.012686,
.00675,-.011691,
.008678,-.010342,
.010342,-.008678,
.011691,-.00675,
.012686,-.004617,
.013295,-.002344,
.0135,0.0,
.013295,.002344,
.012686,.004617,
.011691,.00675,
.010342,.008678,
.008678,.010342,
.00675,.011691,
.004617,.012686,
.002344,.013295,
0.0,.0135,
270.*
%
%ADD26MACRO26*%
%AMMACRO22*
4,1,36,0.0,.0135,
-.002344,.013295,
-.004617,.012686,
-.00675,.011691,
-.008678,.010342,
-.010342,.008678,
-.011691,.00675,
-.012686,.004617,
-.013295,.002344,
-.0135,0.0,
-.013295,-.002344,
-.012686,-.004617,
-.011691,-.00675,
-.010342,-.008678,
-.008678,-.010342,
-.00675,-.011691,
-.004617,-.012686,
-.002344,-.013295,
0.0,-.0135,
.002344,-.013295,
.004617,-.012686,
.00675,-.011691,
.008678,-.010342,
.010342,-.008678,
.011691,-.00675,
.012686,-.004617,
.013295,-.002344,
.0135,0.0,
.013295,.002344,
.012686,.004617,
.011691,.00675,
.010342,.008678,
.008678,.010342,
.00675,.011691,
.004617,.012686,
.002344,.013295,
0.0,.0135,
180.*
%
%ADD22MACRO22*%
%AMMACRO24*
4,1,36,.0025,0.0,
.002462,.000434,
.002349,.000855,
.002165,.00125,
.001915,.001607,
.001607,.001915,
.00125,.002165,
.000855,.002349,
.000434,.002462,
0.0,.0025,
-.000434,.002462,
-.000855,.002349,
-.00125,.002165,
-.001607,.001915,
-.001915,.001607,
-.002165,.00125,
-.002349,.000855,
-.002462,.000434,
-.0025,0.0,
-.002462,-.000434,
-.002349,-.000855,
-.002165,-.00125,
-.001915,-.001607,
-.001607,-.001915,
-.00125,-.002165,
-.000855,-.002349,
-.000434,-.002462,
0.0,-.0025,
.000434,-.002462,
.000855,-.002349,
.00125,-.002165,
.001607,-.001915,
.001915,-.001607,
.002165,-.00125,
.002349,-.000855,
.002462,-.000434,
.0025,0.0,
90.*
%
%ADD24MACRO24*%
%ADD36C,.187*%
%AMMACRO33*
4,1,36,0.0,.019,
-.003299,.018711,
-.006498,.017854,
-.0095,.016454,
-.012213,.014555,
-.014555,.012213,
-.016454,.0095,
-.017854,.006498,
-.018711,.003299,
-.019,0.0,
-.018711,-.003299,
-.017854,-.006498,
-.016454,-.0095,
-.014555,-.012213,
-.012213,-.014555,
-.0095,-.016454,
-.006498,-.017854,
-.003299,-.018711,
0.0,-.019,
.003299,-.018711,
.006498,-.017854,
.0095,-.016454,
.012213,-.014555,
.014555,-.012213,
.016454,-.0095,
.017854,-.006498,
.018711,-.003299,
.019,0.0,
.018711,.003299,
.017854,.006498,
.016454,.0095,
.014555,.012213,
.012213,.014555,
.0095,.016454,
.006498,.017854,
.003299,.018711,
0.0,.019,
180.*
%
%ADD33MACRO33*%
%AMMACRO11*
4,1,36,.0025,0.0,
.002462,.000434,
.002349,.000855,
.002165,.00125,
.001915,.001607,
.001607,.001915,
.00125,.002165,
.000855,.002349,
.000434,.002462,
0.0,.0025,
-.000434,.002462,
-.000855,.002349,
-.00125,.002165,
-.001607,.001915,
-.001915,.001607,
-.002165,.00125,
-.002349,.000855,
-.002462,.000434,
-.0025,0.0,
-.002462,-.000434,
-.002349,-.000855,
-.002165,-.00125,
-.001915,-.001607,
-.001607,-.001915,
-.00125,-.002165,
-.000855,-.002349,
-.000434,-.002462,
0.0,-.0025,
.000434,-.002462,
.000855,-.002349,
.00125,-.002165,
.001607,-.001915,
.001915,-.001607,
.002165,-.00125,
.002349,-.000855,
.002462,-.000434,
.0025,0.0,
0.0*
%
%ADD11MACRO11*%
%ADD16C,.188*%
%AMMACRO44*
4,1,21,-.0075,-.06379,
-.0075,-.0709,
-.015443,-.068892,
-.022917,-.065536,
-.029695,-.060932,
-.03557,-.055222,
-.040364,-.048578,
-.043932,-.041203,
-.046165,-.03332,
-.046995,-.025169,
-.047,-.0245,
-.047,-.0075,
-.04,-.0075,
-.04,-.0245,
-.039392,-.031446,
-.037588,-.038181,
-.034641,-.0445,
-.030642,-.050211,
-.025712,-.055141,
-.02,-.05914,
-.013681,-.062087,
-.0075,-.06379,
90.*
4,1,21,.0075,-.0709,
.0075,-.06379,
.014209,-.061891,
.020486,-.058856,
.02614,-.054776,
.031001,-.049777,
.034919,-.04401,
.037776,-.03765,
.039486,-.030891,
.04,-.0245,
.04,-.0075,
.047,-.0075,
.047,-.0245,
.046286,-.032662,
.044165,-.040576,
.040703,-.048001,
.036003,-.054713,
.03021,-.060506,
.023499,-.065205,
.016073,-.068668,
.008159,-.070789,
.0075,-.0709,
90.*
4,1,21,-.0075,.0709,
-.0075,.06379,
-.014209,.061891,
-.020486,.058856,
-.02614,.054776,
-.031001,.049777,
-.034919,.04401,
-.037776,.03765,
-.039486,.030891,
-.04,.0245,
-.04,.0075,
-.047,.0075,
-.047,.0245,
-.046286,.032662,
-.044165,.040576,
-.040703,.048001,
-.036003,.054713,
-.03021,.060506,
-.023499,.065205,
-.016073,.068668,
-.008159,.070789,
-.0075,.0709,
90.*
4,1,21,.0075,.06379,
.0075,.0709,
.015443,.068892,
.022917,.065536,
.029695,.060932,
.03557,.055222,
.040364,.048578,
.043932,.041203,
.046165,.03332,
.046995,.025169,
.047,.0245,
.047,.0075,
.04,.0075,
.04,.0245,
.039392,.031446,
.037588,.038181,
.034641,.0445,
.030642,.050211,
.025712,.055141,
.02,.05914,
.013681,.062087,
.0075,.06379,
90.*
%
%ADD44MACRO44*%
%AMMACRO39*
4,1,16,.02657,.01597,
.02894,.011114,
.03043,.005919,
.030995,.000545,
.030619,-.004845,
.029313,-.010088,
.027115,-.015025,
.02657,-.01597,
.03164,-.02104,
.034813,-.015226,
.036928,-.00895,
.037921,-.002401,
.037762,.00422,
.036455,.010713,
.034041,.016881,
.03164,.02104,
.02657,.01597,
270.*
4,1,16,.01597,-.02657,
.011114,-.02894,
.005919,-.03043,
.000545,-.030995,
-.004845,-.030619,
-.010088,-.029313,
-.015025,-.027115,
-.01597,-.02657,
-.02104,-.03164,
-.015226,-.034813,
-.00895,-.036928,
-.002401,-.037921,
.00422,-.037762,
.010713,-.036455,
.016881,-.034041,
.02104,-.03164,
.01597,-.02657,
270.*
4,1,16,-.02657,-.01597,
-.02894,-.011114,
-.03043,-.005919,
-.030995,-.000545,
-.030619,.004845,
-.029313,.010088,
-.027115,.015025,
-.02657,.01597,
-.03164,.02104,
-.034813,.015226,
-.036928,.00895,
-.037921,.002401,
-.037762,-.00422,
-.036455,-.010713,
-.034041,-.016881,
-.03164,-.02104,
-.02657,-.01597,
270.*
4,1,16,-.01597,.02657,
-.011114,.02894,
-.005919,.03043,
-.000545,.030995,
.004845,.030619,
.010088,.029313,
.015025,.027115,
.01597,.02657,
.02104,.03164,
.015226,.034813,
.00895,.036928,
.002401,.037921,
-.00422,.037762,
-.010713,.036455,
-.016881,.034041,
-.02104,.03164,
-.01597,.02657,
270.*
%
%ADD39MACRO39*%
%AMMACRO12*
4,1,18,.10783,.07955,
.120006,.059617,
.128535,.037873,
.133159,.014977,
.133736,-.008373,
.130251,-.031469,
.122807,-.053609,
.111633,-.074119,
.10783,-.07955,
.11284,-.08455,
.125808,-.063671,
.134953,-.040857,
.139997,-.016802,
.140788,.007763,
.137301,.032093,
.129642,.055447,
.118045,.077117,
.11284,.08455,
.10783,.07955,
180.*
4,1,18,.07955,-.10783,
.059617,-.120006,
.037873,-.128535,
.014977,-.133159,
-.008373,-.133736,
-.031469,-.130251,
-.053609,-.122807,
-.074119,-.111633,
-.07955,-.10783,
-.08455,-.11284,
-.063671,-.125808,
-.040857,-.134953,
-.016802,-.139997,
.007763,-.140788,
.032093,-.137301,
.055447,-.129642,
.077117,-.118045,
.08455,-.11284,
.07955,-.10783,
180.*
4,1,18,-.10783,-.07955,
-.120006,-.059617,
-.128535,-.037873,
-.133159,-.014977,
-.133736,.008373,
-.130251,.031469,
-.122807,.053609,
-.111633,.074119,
-.10783,.07955,
-.11284,.08455,
-.125808,.063671,
-.134953,.040857,
-.139997,.016802,
-.140788,-.007763,
-.137301,-.032093,
-.129642,-.055447,
-.118045,-.077117,
-.11284,-.08455,
-.10783,-.07955,
180.*
4,1,18,-.07955,.10783,
-.059617,.120006,
-.037873,.128535,
-.014977,.133159,
.008373,.133736,
.031469,.130251,
.053609,.122807,
.074119,.111633,
.07955,.10783,
.08455,.11284,
.063671,.125808,
.040857,.134953,
.016802,.139997,
-.007763,.140788,
-.032093,.137301,
-.055447,.129642,
-.077117,.118045,
-.08455,.11284,
-.07955,.10783,
180.*
%
%ADD12MACRO12*%
%AMMACRO30*
4,1,15,.03682,.01914,
.039584,.012455,
.041146,.005393,
.041457,-.001834,
.040509,-.009005,
.03833,-.015903,
.03682,-.01914,
.04197,-.0243,
.045552,-.016643,
.04775,-.00848,
.048497,-.000059,
.047771,.008363,
.045593,.016531,
.042029,.024197,
.04197,.0243,
.03682,.01914,
270.*
4,1,15,.01914,-.03682,
.012455,-.039584,
.005393,-.041146,
-.001834,-.041457,
-.009005,-.040509,
-.015903,-.03833,
-.01914,-.03682,
-.0243,-.04197,
-.016643,-.045552,
-.00848,-.04775,
-.000059,-.048497,
.008363,-.047771,
.016531,-.045593,
.024197,-.042029,
.0243,-.04197,
.01914,-.03682,
270.*
4,1,15,-.03682,-.01914,
-.039584,-.012455,
-.041146,-.005393,
-.041457,.001834,
-.040509,.009005,
-.03833,.015903,
-.03682,.01914,
-.04197,.0243,
-.045552,.016643,
-.04775,.00848,
-.048497,.000059,
-.047771,-.008363,
-.045593,-.016531,
-.042029,-.024197,
-.04197,-.0243,
-.03682,-.01914,
270.*
4,1,15,-.01914,.03682,
-.012455,.039584,
-.005393,.041146,
.001834,.041457,
.009005,.040509,
.015903,.03833,
.01914,.03682,
.0243,.04197,
.016643,.045552,
.00848,.04775,
.000059,.048497,
-.008363,.047771,
-.016531,.045593,
-.024197,.042029,
-.0243,.04197,
-.01914,.03682,
270.*
%
%ADD30MACRO30*%
%AMMACRO32*
4,1,15,-.03682,.01914,
-.039584,.012455,
-.041146,.005393,
-.041457,-.001834,
-.040509,-.009005,
-.03833,-.015903,
-.03682,-.01914,
-.04197,-.0243,
-.045552,-.016643,
-.04775,-.00848,
-.048497,-.000059,
-.047771,.008363,
-.045593,.016531,
-.042029,.024197,
-.04197,.0243,
-.03682,.01914,
270.*
4,1,15,-.01914,-.03682,
-.012455,-.039584,
-.005393,-.041146,
.001834,-.041457,
.009005,-.040509,
.015903,-.03833,
.01914,-.03682,
.0243,-.04197,
.016643,-.045552,
.00848,-.04775,
.000059,-.048497,
-.008363,-.047771,
-.016531,-.045593,
-.024197,-.042029,
-.0243,-.04197,
-.01914,-.03682,
270.*
4,1,15,.03682,-.01914,
.039584,-.012455,
.041146,-.005393,
.041457,.001834,
.040509,.009005,
.03833,.015903,
.03682,.01914,
.04197,.0243,
.045552,.016643,
.04775,.00848,
.048497,.000059,
.047771,-.008363,
.045593,-.016531,
.042029,-.024197,
.04197,-.0243,
.03682,-.01914,
270.*
4,1,15,.01914,.03682,
.012455,.039584,
.005393,.041146,
-.001834,.041457,
-.009005,.040509,
-.015903,.03833,
-.01914,.03682,
-.0243,.04197,
-.016643,.045552,
-.00848,.04775,
-.000059,.048497,
.008363,.047771,
.016531,.045593,
.024197,.042029,
.0243,.04197,
.01914,.03682,
270.*
%
%ADD32MACRO32*%
%ADD48C,.02*%
%ADD49C,.006*%
%ADD57C,.0801*%
%ADD56C,.07006*%
%ADD59C,.09558*%
%ADD60C,.11022*%
%ADD58C,.12006*%
%ADD55C,.11708*%
%ADD51C,.12608*%
%ADD54C,.13509*%
%ADD52C,.16506*%
%ADD50C,.28606*%
%ADD53C,.19806*%
G75*
%LPD*%
G75*
G36*
G01X-457143Y-1211429D02*
X4308572D01*
Y2242857D01*
X-457143D01*
Y-1211429D01*
G37*
%LPC*%
G75*
G36*
G01X1854331Y516776D02*
G02X1872012Y499095I-1J-17682D01*
G01Y85709D01*
G02X1854331Y68028I-17681J0D01*
G01X1751968D01*
G03X1730279Y46339I1J-21690D01*
G01Y19685D01*
G02X1712598Y2004I-17681J0D01*
G01X19685D01*
G02X2004Y19685I0J17681D01*
G01Y603543D01*
G02X19685Y621224I17681J0D01*
G01X102362D01*
G03X124051Y642913I0J21689D01*
G01Y656102D01*
G02X141732Y673783I17681J0D01*
G01X295276D01*
G02X312957Y656102I0J-17681D01*
G01Y634965D01*
G03X326698Y621224I14799J1058D01*
G01X328740D01*
G02X346421Y603543I0J-17681D01*
G01Y435039D01*
G03X377952Y403508I31532J1D01*
G01X1252385D01*
X1252389Y403512D01*
X1256109D01*
X1256113Y403508D01*
X1354331D01*
G03X1385862Y435039I0J31531D01*
G01Y603543D01*
G02X1403543Y621224I17681J0D01*
G01X1405512D01*
G03X1419327Y635039I0J13815D01*
G01Y656102D01*
G02X1437008Y673783I17681J0D01*
G01X1590551D01*
G02X1608232Y656102I0J-17681D01*
G01Y642913D01*
G03X1629921Y621224I21689J0D01*
G01X1712598D01*
G02X1730279Y603543I0J-17681D01*
G01Y538465D01*
G03X1751968Y516776I21690J0D01*
G01X1854331D01*
G37*
G36*
G01X1866142Y783851D02*
G02X1872016Y777977I0J-5874D01*
G01Y534528D01*
G02X1866142Y528654I-5874J0D01*
G01X1751968D01*
G02X1742157Y538465I1J9811D01*
G01Y603543D01*
G03X1712598Y633102I-29559J0D01*
G01X1640064D01*
G02X1630253Y642913I0J9811D01*
G01Y738607D01*
G03X1620379Y748481I-9874J0D01*
G01X1383858D01*
G03X1373984Y738607I0J-9874D01*
G01Y435039D01*
G02X1354331Y415386I-19653J0D01*
G01X1154764D01*
G02X1148890Y421260I0J5874D01*
G01Y479449D01*
G03X1135079Y493260I-13811J0D01*
G01X550827D01*
G03X537016Y479449I0J-13811D01*
G01Y421260D01*
G02X531142Y415386I-5874J0D01*
G01X377952D01*
G02X358299Y435039I0J19653D01*
G01Y738607D01*
G03X348425Y748481I-9874J0D01*
G01X111905D01*
G03X102031Y738607I0J-9874D01*
G01Y642913D01*
G02X92220Y633102I-9811J0D01*
G01X7874D01*
G02X2000Y638976I0J5874D01*
G01Y777977D01*
G02X7874Y783851I5874J0D01*
G01X1866142D01*
G37*
%LPD*%
G75*
G36*
G01X695332Y327292D02*
G02X696613Y327534I1279J-3260D01*
G02X697201Y327485I4J-3502D01*
G03X697254Y327483I34J197D01*
G02X697597Y327500I345J-3483D01*
G01X697600D01*
G02X699019Y327199I-1J-3500D01*
G03X699026Y327196I82J182D01*
G03X699174I74J186D01*
G03X699181Y327199I-75J185D01*
G02X700600Y327500I1420J-3199D01*
G02Y320500I0J-3500D01*
G02X699181Y320801I1J3500D01*
G03X699174Y320804I-82J-182D01*
G03X699026I-74J-186D01*
G03X699019Y320801I75J-185D01*
G02X697600Y320500I-1420J3199D01*
G02X697030Y320547I2J3500D01*
G03X696977Y320548I-30J-198D01*
G01X696975D01*
G02X696613Y320530I-355J3484D01*
G02X695332Y320772I-2J3502D01*
G03X695185I-73J-186D01*
G02X693904Y320530I-1279J3260D01*
G02X692857Y320690I-1J3502D01*
G03X692841Y320694I-56J-192D01*
G03X692732Y320688I-44J-195D01*
G02X691601Y320500I-1132J3312D01*
G01X691600D01*
G02X690181Y320801I1J3500D01*
G03X690174Y320804I-82J-182D01*
G03X690026I-74J-186D01*
G03X690019Y320801I75J-185D01*
G02X688600Y320500I-1420J3199D01*
G02Y327500I0J3500D01*
G02X690019Y327199I-1J-3500D01*
G03X690026Y327196I82J182D01*
G03X690174I74J186D01*
G03X690181Y327199I-75J185D01*
G02X691600Y327500I1420J-3199D01*
G02X692640Y327342I0J-3500D01*
G03X692764Y327344I59J191D01*
G02X693904Y327534I1138J-3312D01*
G02X695185Y327292I2J-3502D01*
G03X695332I73J186D01*
G37*
G36*
G01X1320919Y197645D02*
G02X1320348Y197598I-572J3455D01*
G01X1320346D01*
G02X1323848Y201100I0J3502D01*
G02X1323142Y198991I-3503J0D01*
G03X1323527Y198355I319J-241D01*
G02X1324098Y198402I572J-3455D01*
G01X1324100D01*
G02X1320598Y194900I0J-3502D01*
G02X1321304Y197009I3503J0D01*
G03X1320919Y197645I-319J241D01*
G37*
G36*
G01Y153245D02*
G02X1320348Y153198I-572J3455D01*
G01X1320346D01*
G02X1323848Y156700I0J3502D01*
G02X1323142Y154591I-3503J0D01*
G03X1323527Y153955I319J-241D01*
G02X1324098Y154002I572J-3455D01*
G01X1324100D01*
G02X1320598Y150500I0J-3502D01*
G02X1321304Y152609I3503J0D01*
G03X1320919Y153245I-319J241D01*
G37*
G36*
G01X1563628Y664685D02*
Y664687D01*
G02X1568406Y669464I4778J-1D01*
G02X1572039Y667789I-1J-4779D01*
G03X1572191Y667719I152J130D01*
G01X1572495D01*
G03X1572647Y667789I0J200D01*
G02X1576280Y669464I3634J-3104D01*
G02X1581058Y664685I-1J-4779D01*
G02X1579384Y661052I-4779J0D01*
G03X1579314Y660900I130J-152D01*
G01Y660596D01*
G03X1579384Y660444I200J0D01*
G02Y653178I-3105J-3633D01*
G03X1579314Y653026I130J-152D01*
G01Y652722D01*
G03X1579384Y652570I200J0D01*
G02Y645304I-3105J-3633D01*
G03X1579314Y645152I130J-152D01*
G01Y644848D01*
G03X1579384Y644696I200J0D01*
G02Y637430I-3105J-3633D01*
G03X1579314Y637278I130J-152D01*
G01Y636974D01*
G03X1579384Y636822I200J0D01*
G02Y629556I-3105J-3633D01*
G03X1579314Y629404I130J-152D01*
G01Y629100D01*
G03X1579384Y628948I200J0D01*
G02Y621682I-3105J-3633D01*
G03X1579314Y621530I130J-152D01*
G01Y621226D01*
G03X1579384Y621074I200J0D01*
G02Y613808I-3105J-3633D01*
G03X1579314Y613656I130J-152D01*
G01Y613352D01*
G03X1579384Y613200I200J0D01*
G02Y605934I-3105J-3633D01*
G03X1579314Y605782I130J-152D01*
G01Y605478D01*
G03X1579384Y605326I200J0D01*
G02X1581058Y601693I-3105J-3633D01*
G01Y601691D01*
G02X1576280Y596914I-4778J1D01*
G02X1572647Y598589I1J4779D01*
G03X1572495Y598659I-152J-130D01*
G01X1572191D01*
G03X1572039Y598589I0J-200D01*
G02X1568406Y596914I-3634J3104D01*
G02X1563628Y601693I1J4779D01*
G02X1565302Y605326I4779J0D01*
G03X1565372Y605478I-130J152D01*
G01Y605782D01*
G03X1565302Y605934I-200J0D01*
G02Y613200I3105J3633D01*
G03X1565372Y613352I-130J152D01*
G01Y613656D01*
G03X1565302Y613808I-200J0D01*
G02Y621074I3105J3633D01*
G03X1565372Y621226I-130J152D01*
G01Y621530D01*
G03X1565302Y621682I-200J0D01*
G02Y628948I3105J3633D01*
G03X1565372Y629100I-130J152D01*
G01Y629404D01*
G03X1565302Y629556I-200J0D01*
G02Y636822I3105J3633D01*
G03X1565372Y636974I-130J152D01*
G01Y637278D01*
G03X1565302Y637430I-200J0D01*
G02Y644696I3105J3633D01*
G03X1565372Y644848I-130J152D01*
G01Y645152D01*
G03X1565302Y645304I-200J0D01*
G02Y652570I3105J3633D01*
G03X1565372Y652722I-130J152D01*
G01Y653026D01*
G03X1565302Y653178I-200J0D01*
G02Y660444I3105J3633D01*
G03X1565372Y660596I-130J152D01*
G01Y660900D01*
G03X1565302Y661052I-200J0D01*
G02X1563628Y664685I3105J3633D01*
G37*
G36*
G01X132524D02*
G02X137303Y669464I4779J0D01*
G02X140936Y667789I-1J-4779D01*
G03X141088Y667719I152J130D01*
G01X141392D01*
G03X141544Y667789I0J200D01*
G02X145177Y669464I3634J-3104D01*
G02X149956Y664685I0J-4779D01*
G02X148281Y661052I-4779J1D01*
G03X148211Y660900I130J-152D01*
G01Y660596D01*
G03X148281Y660444I200J0D01*
G02X149956Y656811I-3104J-3634D01*
G02X148281Y653178I-4779J1D01*
G03X148211Y653026I130J-152D01*
G01Y652722D01*
G03X148281Y652570I200J0D01*
G02X149956Y648937I-3104J-3634D01*
G02X148281Y645304I-4779J1D01*
G03X148211Y645152I130J-152D01*
G01Y644848D01*
G03X148281Y644696I200J0D01*
G02X149956Y641063I-3104J-3634D01*
G02X148281Y637430I-4779J1D01*
G03X148211Y637278I130J-152D01*
G01Y636974D01*
G03X148281Y636822I200J0D01*
G02X149956Y633189I-3104J-3634D01*
G02X148281Y629556I-4779J1D01*
G03X148211Y629404I130J-152D01*
G01Y629100D01*
G03X148281Y628948I200J0D01*
G02X149956Y625315I-3104J-3634D01*
G02X148281Y621682I-4779J1D01*
G03X148211Y621530I130J-152D01*
G01Y621226D01*
G03X148281Y621074I200J0D01*
G02X149956Y617441I-3104J-3634D01*
G02X148281Y613808I-4779J1D01*
G03X148211Y613656I130J-152D01*
G01Y613352D01*
G03X148281Y613200I200J0D01*
G02X149956Y609567I-3104J-3634D01*
G02X148281Y605934I-4779J1D01*
G03X148211Y605782I130J-152D01*
G01Y605478D01*
G03X148281Y605326I200J0D01*
G02X149956Y601693I-3104J-3634D01*
G02X145177Y596914I-4779J0D01*
G02X141544Y598589I1J4779D01*
G03X141392Y598659I-152J-130D01*
G01X141088D01*
G03X140936Y598589I0J-200D01*
G02X137303Y596914I-3634J3104D01*
G02X132524Y601693I0J4779D01*
G02X134199Y605326I4779J-1D01*
G03X134269Y605478I-130J152D01*
G01Y605782D01*
G03X134199Y605934I-200J0D01*
G02X132524Y609567I3104J3634D01*
G02X134199Y613200I4779J-1D01*
G03X134269Y613352I-130J152D01*
G01Y613656D01*
G03X134199Y613808I-200J0D01*
G02X132524Y617441I3104J3634D01*
G02X134199Y621074I4779J-1D01*
G03X134269Y621226I-130J152D01*
G01Y621530D01*
G03X134199Y621682I-200J0D01*
G02X132524Y625315I3104J3634D01*
G02X134199Y628948I4779J-1D01*
G03X134269Y629100I-130J152D01*
G01Y629404D01*
G03X134199Y629556I-200J0D01*
G02X132524Y633189I3104J3634D01*
G02X134199Y636822I4779J-1D01*
G03X134269Y636974I-130J152D01*
G01Y637278D01*
G03X134199Y637430I-200J0D01*
G02X132524Y641063I3104J3634D01*
G02X134199Y644696I4779J-1D01*
G03X134269Y644848I-130J152D01*
G01Y645152D01*
G03X134199Y645304I-200J0D01*
G02X132524Y648937I3104J3634D01*
G02X134199Y652570I4779J-1D01*
G03X134269Y652722I-130J152D01*
G01Y653026D01*
G03X134199Y653178I-200J0D01*
G02X132524Y656811I3104J3634D01*
G02X134199Y660444I4779J-1D01*
G03X134269Y660596I-130J152D01*
G01Y660900D01*
G03X134199Y661052I-200J0D01*
G02X132524Y664685I3104J3634D01*
G37*
G36*
G01X1530076Y638108D02*
X1530067Y638055D01*
X1530104Y637954D01*
X1530455Y637664D01*
X1530559Y637646D01*
X1530610Y637665D01*
G02X1532283Y637968I1675J-4476D01*
G02X1535916Y636293I-1J-4779D01*
G03X1536068Y636223I152J130D01*
G01X1536372D01*
G03X1536524Y636293I0J200D01*
G02X1540157Y637968I3634J-3104D01*
G02X1544936Y633189I0J-4779D01*
G02X1543261Y629556I-4779J1D01*
G03X1543191Y629404I130J-152D01*
G01Y629100D01*
G03X1543261Y628948I200J0D01*
G02X1544936Y625315I-3104J-3634D01*
G02X1543261Y621682I-4779J1D01*
G03X1543191Y621530I130J-152D01*
G01Y621226D01*
G03X1543261Y621074I200J0D01*
G02X1544936Y617441I-3104J-3634D01*
G02X1540157Y612662I-4779J0D01*
G02X1536524Y614337I1J4779D01*
G03X1536372Y614407I-152J-130D01*
G01X1536068D01*
G03X1535916Y614337I0J-200D01*
G02X1532283Y612662I-3634J3104D01*
G02X1527504Y617441I0J4779D01*
G02X1529179Y621074I4779J-1D01*
G03X1529249Y621226I-130J152D01*
G01Y621530D01*
G03X1529179Y621682I-200J0D01*
G02X1527504Y625315I3104J3634D01*
G02X1529179Y628948I4779J-1D01*
G03X1529249Y629100I-130J152D01*
G01Y629404D01*
G03X1529179Y629556I-200J0D01*
G02X1527504Y633189I3104J3634D01*
G02X1527518Y633540I4778J-15D01*
G01Y633542D01*
G03X1527431Y633722I-200J15D01*
G01X1527143Y633916D01*
G03X1526943Y633931I-113J-165D01*
G01X1526942Y633930D01*
G02X1521876I-2533J5164D01*
G01X1521875Y633931D01*
G03X1521675Y633916I-87J-180D01*
G01X1521387Y633722D01*
G03X1521300Y633542I113J-165D01*
G01Y633541D01*
G02X1521314Y633189I-4764J-366D01*
G02X1519639Y629556I-4779J1D01*
G03X1519569Y629404I130J-152D01*
G01Y629100D01*
G03X1519639Y628948I200J0D01*
G02X1521314Y625315I-3104J-3634D01*
G02X1519639Y621682I-4779J1D01*
G03X1519569Y621530I130J-152D01*
G01Y621226D01*
G03X1519639Y621074I200J0D01*
G02X1521314Y617441I-3104J-3634D01*
G02X1516535Y612662I-4779J0D01*
G02X1512902Y614337I1J4779D01*
G03X1512750Y614407I-152J-130D01*
G01X1512446D01*
G03X1512294Y614337I0J-200D01*
G02X1508661Y612662I-3634J3104D01*
G02X1503882Y617441I0J4779D01*
G02X1505557Y621074I4779J-1D01*
G03X1505627Y621226I-130J152D01*
G01Y621530D01*
G03X1505557Y621682I-200J0D01*
G02X1503882Y625315I3104J3634D01*
G02X1505557Y628948I4779J-1D01*
G03X1505627Y629100I-130J152D01*
G01Y629404D01*
G03X1505557Y629556I-200J0D01*
G02X1503882Y633189I3104J3634D01*
G02X1508661Y637968I4779J0D01*
G02X1512294Y636293I-1J-4779D01*
G03X1512446Y636223I152J130D01*
G01X1512750D01*
G03X1512902Y636293I0J200D01*
G02X1516535Y637968I3634J-3104D01*
G02X1518208Y637665I-2J-4779D01*
G01X1518259Y637646D01*
X1518363Y637664D01*
X1518714Y637954D01*
X1518751Y638055D01*
X1518742Y638108D01*
G02X1530076I5667J986D01*
G37*
G36*
G01X213541D02*
X213532Y638055D01*
X213569Y637954D01*
X213920Y637664D01*
X214024Y637646D01*
X214075Y637665D01*
G02X215748Y637968I1675J-4476D01*
G02X219381Y636293I-1J-4779D01*
G03X219533Y636223I152J130D01*
G01X219837D01*
G03X219989Y636293I0J200D01*
G02X223622Y637968I3634J-3104D01*
G02X228400Y633189I-1J-4779D01*
G02X226726Y629556I-4779J0D01*
G03X226656Y629404I130J-152D01*
G01Y629100D01*
G03X226726Y628948I200J0D01*
G02Y621682I-3105J-3633D01*
G03X226656Y621530I130J-152D01*
G01Y621226D01*
G03X226726Y621074I200J0D01*
G02X228400Y617441I-3105J-3633D01*
G01Y617439D01*
G02X223622Y612662I-4778J1D01*
G02X219989Y614337I1J4779D01*
G03X219837Y614407I-152J-130D01*
G01X219533D01*
G03X219381Y614337I0J-200D01*
G02X215748Y612662I-3634J3104D01*
G02X210970Y617441I1J4779D01*
G02X212644Y621074I4779J0D01*
G03X212714Y621226I-130J152D01*
G01Y621530D01*
G03X212644Y621682I-200J0D01*
G02Y628948I3105J3633D01*
G03X212714Y629100I-130J152D01*
G01Y629404D01*
G03X212644Y629556I-200J0D01*
G02X210970Y633189I3105J3633D01*
G02X210983Y633541I4778J0D01*
G01Y633542D01*
G03X210896Y633722I-200J15D01*
G01X210608Y633916D01*
G03X210408Y633931I-113J-165D01*
G01X210407Y633930D01*
G02X205341I-2533J5164D01*
G01X205340Y633931D01*
G03X205140Y633916I-87J-180D01*
G01X204852Y633722D01*
G03X204765Y633542I113J-165D01*
G01Y633541D01*
G02X204778Y633189I-4765J-352D01*
G02X203104Y629556I-4779J0D01*
G03X203034Y629404I130J-152D01*
G01Y629100D01*
G03X203104Y628948I200J0D01*
G02Y621682I-3105J-3633D01*
G03X203034Y621530I130J-152D01*
G01Y621226D01*
G03X203104Y621074I200J0D01*
G02X204778Y617441I-3105J-3633D01*
G01Y617439D01*
G02X200000Y612662I-4778J1D01*
G02X196367Y614337I1J4779D01*
G03X196215Y614407I-152J-130D01*
G01X195911D01*
G03X195759Y614337I0J-200D01*
G02X192126Y612662I-3634J3104D01*
G02X187348Y617441I1J4779D01*
G02X189022Y621074I4779J0D01*
G03X189092Y621226I-130J152D01*
G01Y621530D01*
G03X189022Y621682I-200J0D01*
G02Y628948I3105J3633D01*
G03X189092Y629100I-130J152D01*
G01Y629404D01*
G03X189022Y629556I-200J0D01*
G02X187348Y633189I3105J3633D01*
G01Y633191D01*
G02X192126Y637968I4778J-1D01*
G02X195759Y636293I-1J-4779D01*
G03X195911Y636223I152J130D01*
G01X196215D01*
G03X196367Y636293I0J200D01*
G02X200000Y637968I3634J-3104D01*
G02X201673Y637665I-2J-4779D01*
G01X201724Y637646D01*
X201828Y637664D01*
X202179Y637954D01*
X202216Y638055D01*
X202207Y638108D01*
G02X213541I5667J986D01*
G37*
G36*
G01X1476378Y637968D02*
G02X1480011Y636293I-1J-4779D01*
G03X1480163Y636223I152J130D01*
G01X1480467D01*
G03X1480619Y636293I0J200D01*
G02X1484252Y637968I3634J-3104D01*
G02X1489030Y633189I-1J-4779D01*
G02X1487356Y629556I-4779J0D01*
G03X1487286Y629404I130J-152D01*
G01Y629100D01*
G03X1487356Y628948I200J0D01*
G02Y621682I-3105J-3633D01*
G03X1487286Y621530I130J-152D01*
G01Y621226D01*
G03X1487356Y621074I200J0D01*
G02X1489030Y617441I-3105J-3633D01*
G01Y617439D01*
G02X1484252Y612662I-4778J1D01*
G02X1480619Y614337I1J4779D01*
G03X1480467Y614407I-152J-130D01*
G01X1480163D01*
G03X1480011Y614337I0J-200D01*
G02X1476378Y612662I-3634J3104D01*
G02X1471600Y617441I1J4779D01*
G02X1473274Y621074I4779J0D01*
G03X1473344Y621226I-130J152D01*
G01Y621530D01*
G03X1473274Y621682I-200J0D01*
G02X1472062Y623263I3103J3634D01*
G01X1472044Y623301D01*
X1471981Y623356D01*
X1471657Y623454D01*
G03X1471497Y623435I-58J-191D01*
G02X1465511I-2993J5030D01*
G03X1465351Y623454I-102J-172D01*
G01X1465027Y623356D01*
X1464964Y623301D01*
X1464946Y623263D01*
G02X1463734Y621682I-4315J2053D01*
G03X1463664Y621530I130J-152D01*
G01Y621226D01*
G03X1463734Y621074I200J0D01*
G02X1465408Y617441I-3105J-3633D01*
G01Y617439D01*
G02X1460630Y612662I-4778J1D01*
G02X1456997Y614337I1J4779D01*
G03X1456845Y614407I-152J-130D01*
G01X1456541D01*
G03X1456389Y614337I0J-200D01*
G02X1452756Y612662I-3634J3104D01*
G02X1447978Y617441I1J4779D01*
G02X1449652Y621074I4779J0D01*
G03X1449722Y621226I-130J152D01*
G01Y621530D01*
G03X1449652Y621682I-200J0D01*
G02Y628948I3105J3633D01*
G03X1449722Y629100I-130J152D01*
G01Y629404D01*
G03X1449652Y629556I-200J0D01*
G02X1447978Y633189I3105J3633D01*
G01Y633191D01*
G02X1452756Y637968I4778J-1D01*
G02X1456389Y636293I-1J-4779D01*
G03X1456541Y636223I152J130D01*
G01X1456845D01*
G03X1456997Y636293I0J200D01*
G02X1460630Y637968I3634J-3104D01*
G02X1465339Y634002I0J-4779D01*
G03X1465445Y633857I197J33D01*
G01X1465731Y633712D01*
G03X1465910Y633711I90J178D01*
G02X1471098I2594J-5246D01*
G01X1471141Y633690D01*
X1471234Y633691D01*
X1471563Y633857D01*
G03X1471669Y634002I-91J178D01*
G02X1476378Y637968I4709J-813D01*
G37*
G36*
G01X1424356Y633189D02*
Y633191D01*
G02X1429134Y637968I4778J-1D01*
G02X1432767Y636293I-1J-4779D01*
G03X1432919Y636223I152J130D01*
G01X1433223D01*
G03X1433375Y636293I0J200D01*
G02X1437008Y637968I3634J-3104D01*
G02X1441786Y633189I-1J-4779D01*
G02X1440112Y629556I-4779J0D01*
G03X1440042Y629404I130J-152D01*
G01Y629100D01*
G03X1440112Y628948I200J0D01*
G02Y621682I-3105J-3633D01*
G03X1440042Y621530I130J-152D01*
G01Y621226D01*
G03X1440112Y621074I200J0D01*
G02X1441786Y617441I-3105J-3633D01*
G01Y617439D01*
G02X1437008Y612662I-4778J1D01*
G02X1433375Y614337I1J4779D01*
G03X1433223Y614407I-152J-130D01*
G01X1432919D01*
G03X1432767Y614337I0J-200D01*
G02X1429134Y612662I-3634J3104D01*
G02X1424356Y617441I1J4779D01*
G02X1426030Y621074I4779J0D01*
G03X1426100Y621226I-130J152D01*
G01Y621530D01*
G03X1426030Y621682I-200J0D01*
G02Y628948I3105J3633D01*
G03X1426100Y629100I-130J152D01*
G01Y629404D01*
G03X1426030Y629556I-200J0D01*
G02X1424356Y633189I3105J3633D01*
G37*
G36*
G01X295276Y637968D02*
G02X298909Y636293I-1J-4779D01*
G03X299061Y636223I152J130D01*
G01X299365D01*
G03X299517Y636293I0J200D01*
G02X303150Y637968I3634J-3104D01*
G02X307928Y633189I-1J-4779D01*
G02X306254Y629556I-4779J0D01*
G03X306184Y629404I130J-152D01*
G01Y629100D01*
G03X306254Y628948I200J0D01*
G02Y621682I-3105J-3633D01*
G03X306184Y621530I130J-152D01*
G01Y621226D01*
G03X306254Y621074I200J0D01*
G02X307928Y617441I-3105J-3633D01*
G01Y617439D01*
G02X303150Y612662I-4778J1D01*
G02X299517Y614337I1J4779D01*
G03X299365Y614407I-152J-130D01*
G01X299061D01*
G03X298909Y614337I0J-200D01*
G02X295276Y612662I-3634J3104D01*
G02X290498Y617441I1J4779D01*
G02X292172Y621074I4779J0D01*
G03X292242Y621226I-130J152D01*
G01Y621530D01*
G03X292172Y621682I-200J0D01*
G02X290960Y623263I3103J3634D01*
G01X290942Y623301D01*
X290879Y623356D01*
X290555Y623454D01*
G03X290395Y623435I-58J-191D01*
G02X284409I-2993J5030D01*
G03X284249Y623454I-102J-172D01*
G01X283925Y623356D01*
X283862Y623301D01*
X283844Y623263D01*
G02X282632Y621682I-4315J2053D01*
G03X282562Y621530I130J-152D01*
G01Y621226D01*
G03X282632Y621074I200J0D01*
G02X284306Y617441I-3105J-3633D01*
G01Y617439D01*
G02X279528Y612662I-4778J1D01*
G02X275895Y614337I1J4779D01*
G03X275743Y614407I-152J-130D01*
G01X275439D01*
G03X275287Y614337I0J-200D01*
G02X271654Y612662I-3634J3104D01*
G02X266876Y617441I1J4779D01*
G02X268550Y621074I4779J0D01*
G03X268620Y621226I-130J152D01*
G01Y621530D01*
G03X268550Y621682I-200J0D01*
G02Y628948I3105J3633D01*
G03X268620Y629100I-130J152D01*
G01Y629404D01*
G03X268550Y629556I-200J0D01*
G02X266876Y633189I3105J3633D01*
G01Y633191D01*
G02X271654Y637968I4778J-1D01*
G02X275287Y636293I-1J-4779D01*
G03X275439Y636223I152J130D01*
G01X275743D01*
G03X275895Y636293I0J200D01*
G02X279528Y637968I3634J-3104D01*
G02X284237Y634002I0J-4779D01*
G03X284343Y633857I197J33D01*
G01X284629Y633712D01*
G03X284808Y633711I90J178D01*
G02X289996I2594J-5246D01*
G01X290039Y633690D01*
X290132Y633691D01*
X290461Y633857D01*
G03X290567Y634002I-91J178D01*
G02X295276Y637968I4709J-813D01*
G37*
G36*
G01X243254Y633189D02*
Y633191D01*
G02X248032Y637968I4778J-1D01*
G02X251665Y636293I-1J-4779D01*
G03X251817Y636223I152J130D01*
G01X252121D01*
G03X252273Y636293I0J200D01*
G02X255906Y637968I3634J-3104D01*
G02X260684Y633189I-1J-4779D01*
G02X259010Y629556I-4779J0D01*
G03X258940Y629404I130J-152D01*
G01Y629100D01*
G03X259010Y628948I200J0D01*
G02Y621682I-3105J-3633D01*
G03X258940Y621530I130J-152D01*
G01Y621226D01*
G03X259010Y621074I200J0D01*
G02X260684Y617441I-3105J-3633D01*
G01Y617439D01*
G02X255906Y612662I-4778J1D01*
G02X252273Y614337I1J4779D01*
G03X252121Y614407I-152J-130D01*
G01X251817D01*
G03X251665Y614337I0J-200D01*
G02X248032Y612662I-3634J3104D01*
G02X243254Y617441I1J4779D01*
G02X244928Y621074I4779J0D01*
G03X244998Y621226I-130J152D01*
G01Y621530D01*
G03X244928Y621682I-200J0D01*
G02Y628948I3105J3633D01*
G03X244998Y629100I-130J152D01*
G01Y629404D01*
G03X244928Y629556I-200J0D01*
G02X243254Y633189I3105J3633D01*
G37*
G36*
G01X1084241Y342083D02*
X1084359D01*
G03X1084490Y342133I-1J200D01*
G02X1086800Y343002I2309J-2634D01*
G01X1086803D01*
G02X1087983Y342797I-1J-3502D01*
G03X1088117I67J188D01*
G02X1089297Y343002I1181J-3297D01*
G01X1089300D01*
G02Y335998I0J-3502D01*
G01X1089297D01*
G02X1088117Y336203I1J3502D01*
G03X1087983I-67J-188D01*
G02X1086803Y335998I-1181J3297D01*
G01X1086800D01*
G02X1084490Y336867I-1J3503D01*
G03X1084359Y336917I-132J-150D01*
G01X1084241D01*
G03X1084110Y336867I1J-200D01*
G02X1081800Y335998I-2309J2634D01*
G01X1081797D01*
G02X1080617Y336203I1J3502D01*
G03X1080483I-67J-188D01*
G02X1079303Y335998I-1181J3297D01*
G01X1079300D01*
G02X1076832Y337015I0J3503D01*
G01X1076831Y337016D01*
G03X1076691Y337073I-140J-143D01*
G01X1076409D01*
G03X1076269Y337016I0J-200D01*
G01X1076268Y337015D01*
G02X1073800Y335998I-2468J2486D01*
G01X1073797D01*
G02X1072617Y336203I1J3502D01*
G03X1072483I-67J-188D01*
G02X1071303Y335998I-1181J3297D01*
G01X1071300D01*
G02X1068832Y337015I0J3503D01*
G01X1068831Y337016D01*
G03X1068691Y337073I-140J-143D01*
G01X1068409D01*
G03X1068269Y337016I0J-200D01*
G01X1068268Y337015D01*
G02X1065800Y335998I-2468J2486D01*
G01X1065797D01*
G02X1064617Y336203I1J3502D01*
G03X1064483I-67J-188D01*
G02X1063303Y335998I-1181J3297D01*
G01X1063300D01*
G02Y343002I0J3502D01*
G01X1063303D01*
G02X1064483Y342797I-1J-3502D01*
G03X1064617I67J188D01*
G02X1065797Y343002I1181J-3297D01*
G01X1065800D01*
G02X1068268Y341985I0J-3503D01*
G01X1068269Y341984D01*
G03X1068409Y341927I140J143D01*
G01X1068691D01*
G03X1068831Y341984I0J200D01*
G01X1068832Y341985D01*
G02X1071300Y343002I2468J-2486D01*
G01X1071303D01*
G02X1072483Y342797I-1J-3502D01*
G03X1072617I67J188D01*
G02X1073797Y343002I1181J-3297D01*
G01X1073800D01*
G02X1076268Y341985I0J-3503D01*
G01X1076269Y341984D01*
G03X1076409Y341927I140J143D01*
G01X1076691D01*
G03X1076831Y341984I0J200D01*
G01X1076832Y341985D01*
G02X1079300Y343002I2468J-2486D01*
G01X1079303D01*
G02X1080483Y342797I-1J-3502D01*
G03X1080617I67J188D01*
G02X1081797Y343002I1181J-3297D01*
G01X1081800D01*
G02X1084110Y342133I1J-3503D01*
G03X1084241Y342083I132J150D01*
G37*
G36*
G01X1197534Y318912D02*
Y318914D01*
G02X1201037Y315410I3503J-1D01*
G01X1200968D01*
X1200964D01*
X1200920Y315411D01*
X1200838Y315374D01*
X1200608Y315101D01*
G03X1200565Y314934I153J-129D01*
G02X1200630Y314264I-3438J-672D01*
G01Y314262D01*
G02X1197127Y317766I-3503J1D01*
G01X1197196D01*
X1197200D01*
X1197244Y317765D01*
X1197326Y317802D01*
X1197556Y318075D01*
G03X1197599Y318242I-153J129D01*
G02X1197534Y318912I3438J672D01*
G37*
G36*
G01X1176200Y312998D02*
X1176198D01*
G02X1174781Y313298I1J3502D01*
G03X1174619I-81J-183D01*
G02X1173202Y312998I-1418J3202D01*
G01X1173200D01*
G02Y320002I0J3502D01*
G01X1173202D01*
G02X1174619Y319702I-1J-3502D01*
G03X1174781I81J183D01*
G02X1176198Y320002I1418J-3202D01*
G01X1176200D01*
G02Y312998I0J-3502D01*
G37*
G36*
G01X587182Y310800D02*
Y310802D01*
G02X587482Y312219I3502J-1D01*
G03Y312381I-183J81D01*
G02X587182Y313798I3202J1418D01*
G01Y313800D01*
G02X594186I3502J0D01*
G01Y313798D01*
G02X593886Y312381I-3502J1D01*
G03Y312219I183J-81D01*
G02X594186Y310802I-3202J-1418D01*
G01Y310800D01*
G02X587182I-3502J0D01*
G37*
G36*
G01X1304198Y309900D02*
G02X1304498Y311319I3502J1D01*
G03Y311481I-183J81D01*
G02X1304198Y312898I3202J1418D01*
G01Y312900D01*
G02X1307700Y316402I3502J0D01*
G01X1307702D01*
G02X1309119Y316102I-1J-3502D01*
G03X1309281I81J183D01*
G02X1310698Y316402I1418J-3202D01*
G01X1310700D01*
G02X1314149Y313511I0J-3503D01*
G03X1314311Y313349I197J35D01*
G02X1317149Y310511I-611J-3449D01*
G03X1317311Y310349I197J35D01*
G02X1320149Y307511I-611J-3449D01*
G03X1320311Y307349I197J35D01*
G02X1323202Y303900I-612J-3449D01*
G01Y303898D01*
G02X1322902Y302481I-3502J1D01*
G03Y302319I183J-81D01*
G02X1323202Y300902I-3202J-1418D01*
G01Y300900D01*
G02X1319700Y297398I-3502J0D01*
G01X1319698D01*
G02X1318281Y297698I1J3502D01*
G03X1318119I-81J-183D01*
G02X1316700Y297398I-1418J3202D01*
G02X1315281Y297698I-1J3502D01*
G03X1315119I-81J-183D01*
G02X1313700Y297398I-1418J3202D01*
G02X1312281Y297698I-1J3502D01*
G03X1312119I-81J-183D01*
G02X1310700Y297398I-1418J3202D01*
G02X1309281Y297698I-1J3502D01*
G03X1309119I-81J-183D01*
G02X1307702Y297398I-1418J3202D01*
G01X1307700D01*
G02X1304198Y300900I0J3502D01*
G01Y300902D01*
G02X1304498Y302319I3502J-1D01*
G03Y302481I-183J81D01*
G02X1304198Y303900I3202J1418D01*
G02X1304498Y305319I3502J1D01*
G03Y305481I-183J81D01*
G02X1304198Y306900I3202J1418D01*
G02X1304498Y308319I3502J1D01*
G03Y308481I-183J81D01*
G02X1304198Y309900I3202J1418D01*
G37*
G36*
G01X1106661Y304198D02*
X1106659D01*
G02X1105242Y304498I1J3502D01*
G03X1105080I-81J-183D01*
G02X1103663Y304198I-1418J3202D01*
G01X1103661D01*
G02Y311202I0J3502D01*
G01X1103663D01*
G02X1105080Y310902I-1J-3502D01*
G03X1105242I81J183D01*
G02X1106659Y311202I1418J-3202D01*
G01X1106661D01*
G02Y304198I0J-3502D01*
G37*
G36*
G01X565091Y299090D02*
G02Y306094I0J3502D01*
G01X565092D01*
G02X567440Y305190I0J-3502D01*
G01X567469Y305164D01*
X567540Y305137D01*
X567853Y305143D01*
G03X567989Y305201I-5J200D01*
G02X570442Y306204I2453J-2499D01*
G01X570443D01*
G02Y299200I0J-3502D01*
G01X570442D01*
G02X568094Y300104I0J3502D01*
G01X568065Y300130D01*
X567994Y300157D01*
X567681Y300151D01*
G03X567545Y300093I5J-200D01*
G02X565092Y299090I-2453J2499D01*
G01X565091D01*
G37*
G36*
G01X1840590Y300433D02*
Y300435D01*
G02X1846142Y305986I5552J-1D01*
G02X1851100Y302933I0J-5552D01*
G01X1851125Y302882D01*
X1851221Y302823D01*
X1851693D01*
X1851789Y302882D01*
X1851814Y302933D01*
G02X1856772Y305986I4958J-2499D01*
G02X1862324Y300433I-1J-5553D01*
G02X1859785Y295769I-5553J0D01*
G01X1859742Y295741D01*
X1859693Y295652D01*
Y295214D01*
X1859742Y295125D01*
X1859785Y295097D01*
G02Y285769I-3014J-4664D01*
G01X1859742Y285741D01*
X1859693Y285652D01*
Y285214D01*
X1859742Y285125D01*
X1859785Y285097D01*
G02Y275769I-3014J-4664D01*
G01X1859742Y275741D01*
X1859693Y275652D01*
Y275214D01*
X1859742Y275125D01*
X1859785Y275097D01*
G02X1862324Y270433I-3014J-4664D01*
G01Y270431D01*
G02X1856772Y264880I-5552J1D01*
G02X1851814Y267933I0J5552D01*
G01X1851789Y267984D01*
X1851693Y268043D01*
X1851221D01*
X1851125Y267984D01*
X1851100Y267933D01*
G02X1846142Y264880I-4958J2499D01*
G02X1840590Y270433I1J5553D01*
G02X1843129Y275097I5553J0D01*
G01X1843172Y275125D01*
X1843221Y275214D01*
Y275652D01*
X1843172Y275741D01*
X1843129Y275769D01*
G02Y285097I3014J4664D01*
G01X1843172Y285125D01*
X1843221Y285214D01*
Y285652D01*
X1843172Y285741D01*
X1843129Y285769D01*
G02Y295097I3014J4664D01*
G01X1843172Y295125D01*
X1843221Y295214D01*
Y295652D01*
X1843172Y295741D01*
X1843129Y295769D01*
G02X1840590Y300433I3014J4664D01*
G37*
G36*
G01X1199059Y290701D02*
X1198941D01*
G03X1198810Y290651I1J-200D01*
G02X1196500Y289782I-2309J2634D01*
G02Y296786I0J3502D01*
G02X1198810Y295917I1J-3503D01*
G03X1198941Y295867I132J150D01*
G01X1199059D01*
G03X1199190Y295917I-1J200D01*
G02X1201500Y296786I2309J-2634D01*
G02Y289782I0J-3502D01*
G02X1199190Y290651I-1J3503D01*
G03X1199059Y290701I-132J-150D01*
G37*
G36*
G01X568040Y289065D02*
Y289066D01*
G02X568410Y290633I3502J0D01*
G03X568398Y290832I-179J89D01*
G02X567822Y292757I2926J1924D01*
G02X574828I3503J0D01*
G02X574457Y291189I-3503J1D01*
G03X574469Y290990I179J-89D01*
G02X575044Y289068I-2928J-1923D01*
G01Y289065D01*
G02X568040I-3502J0D01*
G37*
G36*
G01X1055300Y287398D02*
X1055297D01*
G02X1053834Y287719I2J3502D01*
G03X1053666I-84J-182D01*
G02X1052203Y287398I-1465J3181D01*
G01X1052200D01*
G02Y294402I0J3502D01*
G01X1052203D01*
G02X1053666Y294081I-2J-3502D01*
G03X1053834I84J182D01*
G02X1055297Y294402I1465J-3181D01*
G01X1055300D01*
G02Y287398I0J-3502D01*
G37*
G36*
G01X448738Y293502D02*
G02X450157Y293202I1J-3502D01*
G03X450319I81J183D01*
G02X451738Y293502I1418J-3202D01*
G02X453157Y293202I1J-3502D01*
G03X453319I81J183D01*
G02X454736Y293502I1418J-3202D01*
G01X454738D01*
G02X458240Y290000I0J-3502D01*
G01Y289998D01*
G02X457940Y288581I-3502J1D01*
G03Y288419I183J-81D01*
G02X458240Y287000I-3202J-1418D01*
G02X457940Y285581I-3502J-1D01*
G03Y285419I183J-81D01*
G02X458240Y284000I-3202J-1418D01*
G02X457940Y282581I-3502J-1D01*
G03Y282419I183J-81D01*
G02X458240Y281000I-3202J-1418D01*
G02X457940Y279581I-3502J-1D01*
G03Y279419I183J-81D01*
G02X458240Y278002I-3202J-1418D01*
G01Y278000D01*
G02X454738Y274498I-3502J0D01*
G01X454736D01*
G02X453319Y274798I1J3502D01*
G03X453157I-81J-183D01*
G02X451738Y274498I-1418J3202D01*
G02X450319Y274798I-1J3502D01*
G03X450157I-81J-183D01*
G02X448738Y274498I-1418J3202D01*
G02X447319Y274798I-1J3502D01*
G03X447157I-81J-183D01*
G02X445738Y274498I-1418J3202D01*
G02X444319Y274798I-1J3502D01*
G03X444157I-81J-183D01*
G02X442740Y274498I-1418J3202D01*
G01X442738D01*
G02X439236Y278000I0J3502D01*
G01Y278002D01*
G02X439536Y279419I3502J-1D01*
G03Y279581I-183J81D01*
G02X439236Y281000I3202J1418D01*
G02X439536Y282419I3502J1D01*
G03Y282581I-183J81D01*
G02X439236Y284000I3202J1418D01*
G02X439536Y285419I3502J1D01*
G03Y285581I-183J81D01*
G02X439236Y287000I3202J1418D01*
G02X439536Y288419I3502J1D01*
G03Y288581I-183J81D01*
G02X439236Y289998I3202J1418D01*
G01Y290000D01*
G02X442738Y293502I3502J0D01*
G01X442740D01*
G02X444157Y293202I-1J-3502D01*
G03X444319I81J183D01*
G02X445738Y293502I1418J-3202D01*
G02X447157Y293202I1J-3502D01*
G03X447319I81J183D01*
G02X448738Y293502I1418J-3202D01*
G37*
G36*
G01X586796Y282890D02*
G02X593800I3502J0D01*
G02X592588Y280240I-3503J0D01*
G03X592519Y280089I131J-151D01*
G01Y279785D01*
G03X592588Y279634I200J0D01*
G02X593800Y276984I-2291J-2650D01*
G02X586796I-3502J0D01*
G02X588008Y279634I3503J0D01*
G03X588077Y279785I-131J151D01*
G01Y280089D01*
G03X588008Y280240I-200J0D01*
G02X586796Y282890I2291J2650D01*
G37*
G36*
G01X1032500Y278298D02*
X1032498D01*
G02X1031081Y278598I1J3502D01*
G03X1030919I-81J-183D01*
G02X1029502Y278298I-1418J3202D01*
G01X1029500D01*
G02Y285302I0J3502D01*
G01X1029502D01*
G02X1030919Y285002I-1J-3502D01*
G03X1031081I81J183D01*
G02X1032498Y285302I1418J-3202D01*
G01X1032500D01*
G02Y278298I0J-3502D01*
G37*
G36*
G01X1059300Y276098D02*
X1059298D01*
G02X1057550Y276566I1J3502D01*
G03X1057350I-100J-173D01*
G02X1055602Y276098I-1749J3034D01*
G01X1055600D01*
G02Y283102I0J3502D01*
G01X1055602D01*
G02X1057350Y282634I-1J-3502D01*
G03X1057550I100J173D01*
G02X1059298Y283102I1749J-3034D01*
G01X1059300D01*
G02Y276098I0J-3502D01*
G37*
G36*
G01X715982Y278980D02*
G02X722986I3502J0D01*
G02X720657Y275680I-3502J0D01*
G01X720615Y275665D01*
X720553Y275604D01*
X720430Y275276D01*
G03X720442Y275108I187J-71D01*
G02X720886Y273403I-3058J-1707D01*
G01Y273400D01*
G02X713882I-3502J0D01*
G02X716211Y276700I3502J0D01*
G01X716253Y276715D01*
X716315Y276776D01*
X716438Y277104D01*
G03X716426Y277272I-187J71D01*
G02X715982Y278977I3058J1707D01*
G01Y278980D01*
G37*
G36*
G01X1041398Y278600D02*
G02X1048402I3502J0D01*
G02X1046073Y275300I-3502J0D01*
G01X1046031Y275285D01*
X1045969Y275224D01*
X1045846Y274896D01*
G03X1045858Y274728I187J-71D01*
G02X1046302Y273023I-3058J-1707D01*
G01Y273020D01*
G02X1039298I-3502J0D01*
G02X1041627Y276320I3502J0D01*
G01X1041669Y276335D01*
X1041731Y276396D01*
X1041854Y276724D01*
G03X1041842Y276892I-187J71D01*
G02X1041398Y278597I3058J1707D01*
G01Y278600D01*
G37*
G36*
G01X706684Y268898D02*
X706682D01*
G02X704934Y269366I1J3502D01*
G03X704734I-100J-173D01*
G02X702986Y268898I-1749J3034D01*
G01X702984D01*
G02Y275902I0J3502D01*
G01X702986D01*
G02X704734Y275434I-1J-3502D01*
G03X704934I100J173D01*
G02X706682Y275902I1749J-3034D01*
G01X706684D01*
G02Y268898I0J-3502D01*
G37*
G36*
G01X730600Y266498D02*
X730598D01*
G02X729181Y266798I1J3502D01*
G03X729019I-81J-183D01*
G02X727602Y266498I-1418J3202D01*
G01X727600D01*
G02Y273502I0J3502D01*
G01X727602D01*
G02X729019Y273202I-1J-3502D01*
G03X729181I81J183D01*
G02X730598Y273502I1418J-3202D01*
G01X730600D01*
G02Y266498I0J-3502D01*
G37*
G36*
G01X1313700Y272002D02*
G02X1315119Y271702I1J-3502D01*
G03X1315281I81J183D01*
G02X1316700Y272002I1418J-3202D01*
G02X1318119Y271702I1J-3502D01*
G03X1318281I81J183D01*
G02X1319698Y272002I1418J-3202D01*
G01X1319700D01*
G02X1323202Y268500I0J-3502D01*
G01Y268498D01*
G02X1322902Y267081I-3502J1D01*
G03Y266919I183J-81D01*
G02X1323202Y265500I-3202J-1418D01*
G02X1322902Y264081I-3502J-1D01*
G03Y263919I183J-81D01*
G02X1323202Y262500I-3202J-1418D01*
G02X1322902Y261081I-3502J-1D01*
G03Y260919I183J-81D01*
G02X1323202Y259500I-3202J-1418D01*
G02X1322902Y258081I-3502J-1D01*
G03Y257919I183J-81D01*
G02X1323202Y256502I-3202J-1418D01*
G01Y256500D01*
G02X1319700Y252998I-3502J0D01*
G01X1319698D01*
G02X1318281Y253298I1J3502D01*
G03X1318119I-81J-183D01*
G02X1316700Y252998I-1418J3202D01*
G02X1315281Y253298I-1J3502D01*
G03X1315119I-81J-183D01*
G02X1313700Y252998I-1418J3202D01*
G02X1312281Y253298I-1J3502D01*
G03X1312119I-81J-183D01*
G02X1310700Y252998I-1418J3202D01*
G02X1309281Y253298I-1J3502D01*
G03X1309119I-81J-183D01*
G02X1307702Y252998I-1418J3202D01*
G01X1307700D01*
G02X1304198Y256500I0J3502D01*
G01Y256502D01*
G02X1304498Y257919I3502J-1D01*
G03Y258081I-183J81D01*
G02X1304198Y259500I3202J1418D01*
G02X1304498Y260919I3502J1D01*
G03Y261081I-183J81D01*
G02X1304198Y262500I3202J1418D01*
G02X1304498Y263919I3502J1D01*
G03Y264081I-183J81D01*
G02X1304198Y265500I3202J1418D01*
G02X1304498Y266919I3502J1D01*
G03Y267081I-183J81D01*
G02X1304198Y268498I3202J1418D01*
G01Y268500D01*
G02X1307700Y272002I3502J0D01*
G01X1307702D01*
G02X1309119Y271702I-1J-3502D01*
G03X1309281I81J183D01*
G02X1310700Y272002I1418J-3202D01*
G02X1312119Y271702I1J-3502D01*
G03X1312281I81J183D01*
G02X1313700Y272002I1418J-3202D01*
G37*
G36*
G01X1059300Y264998D02*
X1059298D01*
G02X1057550Y265466I1J3502D01*
G03X1057350I-100J-173D01*
G02X1055602Y264998I-1749J3034D01*
G01X1055600D01*
G02Y272002I0J3502D01*
G01X1055602D01*
G02X1057350Y271534I-1J-3502D01*
G03X1057550I100J173D01*
G02X1059298Y272002I1749J-3034D01*
G01X1059300D01*
G02Y264998I0J-3502D01*
G37*
G36*
G01X710084Y257598D02*
X710081D01*
G02X708618Y257919I2J3502D01*
G03X708450I-84J-182D01*
G02X706987Y257598I-1465J3181D01*
G01X706984D01*
G02Y264602I0J3502D01*
G01X706987D01*
G02X708450Y264281I-2J-3502D01*
G03X708618I84J182D01*
G02X710081Y264602I1465J-3181D01*
G01X710084D01*
G02Y257598I0J-3502D01*
G37*
G36*
G01X448738Y249102D02*
G02X450157Y248802I1J-3502D01*
G03X450319I81J183D01*
G02X451738Y249102I1418J-3202D01*
G02X453157Y248802I1J-3502D01*
G03X453319I81J183D01*
G02X454736Y249102I1418J-3202D01*
G01X454738D01*
G02X458240Y245600I0J-3502D01*
G01Y245598D01*
G02X457940Y244181I-3502J1D01*
G03Y244019I183J-81D01*
G02X458240Y242600I-3202J-1418D01*
G02X457940Y241181I-3502J-1D01*
G03Y241019I183J-81D01*
G02X458240Y239600I-3202J-1418D01*
G02X457940Y238181I-3502J-1D01*
G03Y238019I183J-81D01*
G02X458240Y236600I-3202J-1418D01*
G02X457940Y235181I-3502J-1D01*
G03Y235019I183J-81D01*
G02X458240Y233602I-3202J-1418D01*
G01Y233600D01*
G02X454738Y230098I-3502J0D01*
G01X454736D01*
G02X453319Y230398I1J3502D01*
G03X453157I-81J-183D01*
G02X451738Y230098I-1418J3202D01*
G02X450319Y230398I-1J3502D01*
G03X450157I-81J-183D01*
G02X448738Y230098I-1418J3202D01*
G02X447319Y230398I-1J3502D01*
G03X447157I-81J-183D01*
G02X445738Y230098I-1418J3202D01*
G02X444319Y230398I-1J3502D01*
G03X444157I-81J-183D01*
G02X442740Y230098I-1418J3202D01*
G01X442738D01*
G02X439236Y233600I0J3502D01*
G01Y233602D01*
G02X439536Y235019I3502J-1D01*
G03Y235181I-183J81D01*
G02X439236Y236600I3202J1418D01*
G02X439536Y238019I3502J1D01*
G03Y238181I-183J81D01*
G02X439236Y239600I3202J1418D01*
G02X439536Y241019I3502J1D01*
G03Y241181I-183J81D01*
G02X439236Y242600I3202J1418D01*
G02X439536Y244019I3502J1D01*
G03Y244181I-183J81D01*
G02X439236Y245598I3202J1418D01*
G01Y245600D01*
G02X442738Y249102I3502J0D01*
G01X442740D01*
G02X444157Y248802I-1J-3502D01*
G03X444319I81J183D01*
G02X445738Y249102I1418J-3202D01*
G02X447157Y248802I1J-3502D01*
G03X447319I81J183D01*
G02X448738Y249102I1418J-3202D01*
G37*
G36*
G01X658600Y234198D02*
X658598D01*
G02X657181Y234498I1J3502D01*
G03X657019I-81J-183D01*
G02X655602Y234198I-1418J3202D01*
G01X655600D01*
G02Y241202I0J3502D01*
G01X655602D01*
G02X657019Y240902I-1J-3502D01*
G03X657181I81J183D01*
G02X658598Y241202I1418J-3202D01*
G01X658600D01*
G02Y234198I0J-3502D01*
G37*
G36*
G01X1070600Y231502D02*
G02X1072019Y231202I1J-3502D01*
G03X1072181I81J183D01*
G02X1073598Y231502I1418J-3202D01*
G01X1073600D01*
G02Y224498I0J-3502D01*
G01X1073598D01*
G02X1072181Y224798I1J3502D01*
G03X1072019I-81J-183D01*
G02X1070600Y224498I-1418J3202D01*
G02X1067907Y225760I-1J3502D01*
G01X1067879Y225794D01*
X1067799Y225832D01*
X1067401D01*
X1067321Y225794D01*
X1067293Y225760D01*
G02X1064600Y224498I-2692J2240D01*
G02X1063181Y224798I-1J3502D01*
G03X1063019I-81J-183D01*
G02X1061602Y224498I-1418J3202D01*
G01X1061600D01*
G02Y231502I0J3502D01*
G01X1061602D01*
G02X1063019Y231202I-1J-3502D01*
G03X1063181I81J183D01*
G02X1064600Y231502I1418J-3202D01*
G02X1067293Y230240I1J-3502D01*
G01X1067321Y230206D01*
X1067401Y230168D01*
X1067799D01*
X1067879Y230206D01*
X1067907Y230240D01*
G02X1070600Y231502I2692J-2240D01*
G37*
G36*
G01X1313700Y227602D02*
G02X1315119Y227302I1J-3502D01*
G03X1315281I81J183D01*
G02X1316700Y227602I1418J-3202D01*
G02X1318119Y227302I1J-3502D01*
G03X1318281I81J183D01*
G02X1319698Y227602I1418J-3202D01*
G01X1319700D01*
G02X1323202Y224100I0J-3502D01*
G01Y224098D01*
G02X1322902Y222681I-3502J1D01*
G03Y222519I183J-81D01*
G02X1323202Y221100I-3202J-1418D01*
G02X1322902Y219681I-3502J-1D01*
G03Y219519I183J-81D01*
G02X1323202Y218100I-3202J-1418D01*
G02X1322902Y216681I-3502J-1D01*
G03Y216519I183J-81D01*
G02X1323202Y215100I-3202J-1418D01*
G02X1322902Y213681I-3502J-1D01*
G03Y213519I183J-81D01*
G02X1323202Y212102I-3202J-1418D01*
G01Y212100D01*
G02X1319700Y208598I-3502J0D01*
G01X1319698D01*
G02X1318281Y208898I1J3502D01*
G03X1318119I-81J-183D01*
G02X1316700Y208598I-1418J3202D01*
G02X1315281Y208898I-1J3502D01*
G03X1315119I-81J-183D01*
G02X1313700Y208598I-1418J3202D01*
G02X1312281Y208898I-1J3502D01*
G03X1312119I-81J-183D01*
G02X1310700Y208598I-1418J3202D01*
G02X1309281Y208898I-1J3502D01*
G03X1309119I-81J-183D01*
G02X1307702Y208598I-1418J3202D01*
G01X1307700D01*
G02X1304198Y212100I0J3502D01*
G01Y212102D01*
G02X1304498Y213519I3502J-1D01*
G03Y213681I-183J81D01*
G02X1304198Y215100I3202J1418D01*
G02X1304498Y216519I3502J1D01*
G03Y216681I-183J81D01*
G02X1304198Y218100I3202J1418D01*
G02X1304498Y219519I3502J1D01*
G03Y219681I-183J81D01*
G02X1304198Y221100I3202J1418D01*
G02X1304498Y222519I3502J1D01*
G03Y222681I-183J81D01*
G02X1304198Y224098I3202J1418D01*
G01Y224100D01*
G02X1307700Y227602I3502J0D01*
G01X1307702D01*
G02X1309119Y227302I-1J-3502D01*
G03X1309281I81J183D01*
G02X1310700Y227602I1418J-3202D01*
G02X1312119Y227302I1J-3502D01*
G03X1312281I81J183D01*
G02X1313700Y227602I1418J-3202D01*
G37*
G36*
G01X448738Y204702D02*
G02X450157Y204402I1J-3502D01*
G03X450319I81J183D01*
G02X451738Y204702I1418J-3202D01*
G02X453157Y204402I1J-3502D01*
G03X453319I81J183D01*
G02X454736Y204702I1418J-3202D01*
G01X454738D01*
G02X458240Y201200I0J-3502D01*
G01Y201198D01*
G02X457940Y199781I-3502J1D01*
G03Y199619I183J-81D01*
G02X458240Y198200I-3202J-1418D01*
G02X457940Y196781I-3502J-1D01*
G03Y196619I183J-81D01*
G02X458240Y195200I-3202J-1418D01*
G02X457940Y193781I-3502J-1D01*
G03Y193619I183J-81D01*
G02X458240Y192200I-3202J-1418D01*
G02X457940Y190781I-3502J-1D01*
G03Y190619I183J-81D01*
G02X458240Y189202I-3202J-1418D01*
G01Y189200D01*
G02X454738Y185698I-3502J0D01*
G01X454736D01*
G02X453319Y185998I1J3502D01*
G03X453157I-81J-183D01*
G02X451738Y185698I-1418J3202D01*
G02X450319Y185998I-1J3502D01*
G03X450157I-81J-183D01*
G02X448738Y185698I-1418J3202D01*
G02X447319Y185998I-1J3502D01*
G03X447157I-81J-183D01*
G02X445738Y185698I-1418J3202D01*
G02X444319Y185998I-1J3502D01*
G03X444157I-81J-183D01*
G02X442740Y185698I-1418J3202D01*
G01X442738D01*
G02X439236Y189200I0J3502D01*
G01Y189202D01*
G02X439536Y190619I3502J-1D01*
G03Y190781I-183J81D01*
G02X439236Y192200I3202J1418D01*
G02X439536Y193619I3502J1D01*
G03Y193781I-183J81D01*
G02X439236Y195200I3202J1418D01*
G02X439536Y196619I3502J1D01*
G03Y196781I-183J81D01*
G02X439236Y198200I3202J1418D01*
G02X439536Y199619I3502J1D01*
G03Y199781I-183J81D01*
G02X439236Y201198I3202J1418D01*
G01Y201200D01*
G02X442738Y204702I3502J0D01*
G01X442740D01*
G02X444157Y204402I-1J-3502D01*
G03X444319I81J183D01*
G02X445738Y204702I1418J-3202D01*
G02X447157Y204402I1J-3502D01*
G03X447319I81J183D01*
G02X448738Y204702I1418J-3202D01*
G37*
G36*
G01X1307700Y183202D02*
X1307702D01*
G02X1309119Y182902I-1J-3502D01*
G03X1309281I81J183D01*
G02X1310700Y183202I1418J-3202D01*
G02X1312119Y182902I1J-3502D01*
G03X1312281I81J183D01*
G02X1313698Y183202I1418J-3202D01*
G01X1313700D01*
G02X1317149Y180311I0J-3503D01*
G03X1317311Y180149I197J35D01*
G02X1318119Y179902I-612J-3449D01*
G03X1318281I81J183D01*
G02X1319698Y180202I1418J-3202D01*
G01X1319700D01*
G02X1323202Y176700I0J-3502D01*
G01Y176698D01*
G02X1322902Y175281I-3502J1D01*
G03Y175119I183J-81D01*
G02X1323202Y173700I-3202J-1418D01*
G02X1322902Y172281I-3502J-1D01*
G03Y172119I183J-81D01*
G02X1323202Y170700I-3202J-1418D01*
G02X1322902Y169281I-3502J-1D01*
G03Y169119I183J-81D01*
G02X1323202Y167702I-3202J-1418D01*
G01Y167700D01*
G02X1319700Y164198I-3502J0D01*
G01X1319698D01*
G02X1318281Y164498I1J3502D01*
G03X1318119I-81J-183D01*
G02X1316700Y164198I-1418J3202D01*
G02X1315281Y164498I-1J3502D01*
G03X1315119I-81J-183D01*
G02X1313700Y164198I-1418J3202D01*
G02X1312281Y164498I-1J3502D01*
G03X1312119I-81J-183D01*
G02X1310700Y164198I-1418J3202D01*
G02X1309281Y164498I-1J3502D01*
G03X1309119I-81J-183D01*
G02X1307702Y164198I-1418J3202D01*
G01X1307700D01*
G02X1304198Y167700I0J3502D01*
G01Y167702D01*
G02X1304498Y169119I3502J-1D01*
G03Y169281I-183J81D01*
G02X1304198Y170700I3202J1418D01*
G02X1304498Y172119I3502J1D01*
G03Y172281I-183J81D01*
G02X1304198Y173700I3202J1418D01*
G02X1304498Y175119I3502J1D01*
G03Y175281I-183J81D01*
G02X1304198Y176700I3202J1418D01*
G02X1304498Y178119I3502J1D01*
G03Y178281I-183J81D01*
G02X1304198Y179698I3202J1418D01*
G01Y179700D01*
G02X1307700Y183202I3502J0D01*
G37*
G36*
G01X448738Y160302D02*
G02X450157Y160002I1J-3502D01*
G03X450319I81J183D01*
G02X451738Y160302I1418J-3202D01*
G02X453157Y160002I1J-3502D01*
G03X453319I81J183D01*
G02X454736Y160302I1418J-3202D01*
G01X454738D01*
G02X458240Y156800I0J-3502D01*
G01Y156798D01*
G02X457940Y155381I-3502J1D01*
G03Y155219I183J-81D01*
G02X458240Y153800I-3202J-1418D01*
G02X457940Y152381I-3502J-1D01*
G03Y152219I183J-81D01*
G02X458240Y150800I-3202J-1418D01*
G02X457940Y149381I-3502J-1D01*
G03Y149219I183J-81D01*
G02X458240Y147800I-3202J-1418D01*
G02X457940Y146381I-3502J-1D01*
G03Y146219I183J-81D01*
G02X458240Y144802I-3202J-1418D01*
G01Y144800D01*
G02X454738Y141298I-3502J0D01*
G01X454736D01*
G02X453319Y141598I1J3502D01*
G03X453157I-81J-183D01*
G02X451738Y141298I-1418J3202D01*
G02X450319Y141598I-1J3502D01*
G03X450157I-81J-183D01*
G02X448738Y141298I-1418J3202D01*
G02X447319Y141598I-1J3502D01*
G03X447157I-81J-183D01*
G02X445738Y141298I-1418J3202D01*
G02X444319Y141598I-1J3502D01*
G03X444157I-81J-183D01*
G02X442740Y141298I-1418J3202D01*
G01X442738D01*
G02X439236Y144800I0J3502D01*
G01Y144802D01*
G02X439536Y146219I3502J-1D01*
G03Y146381I-183J81D01*
G02X439236Y147800I3202J1418D01*
G02X439536Y149219I3502J1D01*
G03Y149381I-183J81D01*
G02X439236Y150800I3202J1418D01*
G02X439536Y152219I3502J1D01*
G03Y152381I-183J81D01*
G02X439236Y153800I3202J1418D01*
G02X439536Y155219I3502J1D01*
G03Y155381I-183J81D01*
G02X439236Y156798I3202J1418D01*
G01Y156800D01*
G02X442738Y160302I3502J0D01*
G01X442740D01*
G02X444157Y160002I-1J-3502D01*
G03X444319I81J183D01*
G02X445738Y160302I1418J-3202D01*
G02X447157Y160002I1J-3502D01*
G03X447319I81J183D01*
G02X448738Y160302I1418J-3202D01*
G37*
G36*
G01X1313700Y138802D02*
G02X1315119Y138502I1J-3502D01*
G03X1315281I81J183D01*
G02X1316700Y138802I1418J-3202D01*
G02X1318119Y138502I1J-3502D01*
G03X1318281I81J183D01*
G02X1319698Y138802I1418J-3202D01*
G01X1319700D01*
G02X1323202Y135300I0J-3502D01*
G01Y135298D01*
G02X1322902Y133881I-3502J1D01*
G03Y133719I183J-81D01*
G02X1323202Y132300I-3202J-1418D01*
G02X1322902Y130881I-3502J-1D01*
G03Y130719I183J-81D01*
G02X1323202Y129300I-3202J-1418D01*
G02X1322902Y127881I-3502J-1D01*
G03Y127719I183J-81D01*
G02X1323202Y126300I-3202J-1418D01*
G02X1322902Y124881I-3502J-1D01*
G03Y124719I183J-81D01*
G02X1323202Y123302I-3202J-1418D01*
G01Y123300D01*
G02X1319700Y119798I-3502J0D01*
G01X1319698D01*
G02X1318281Y120098I1J3502D01*
G03X1318119I-81J-183D01*
G02X1316700Y119798I-1418J3202D01*
G02X1315281Y120098I-1J3502D01*
G03X1315119I-81J-183D01*
G02X1313700Y119798I-1418J3202D01*
G02X1312281Y120098I-1J3502D01*
G03X1312119I-81J-183D01*
G02X1310700Y119798I-1418J3202D01*
G02X1309281Y120098I-1J3502D01*
G03X1309119I-81J-183D01*
G02X1307702Y119798I-1418J3202D01*
G01X1307700D01*
G02X1304198Y123300I0J3502D01*
G01Y123302D01*
G02X1304498Y124719I3502J-1D01*
G03Y124881I-183J81D01*
G02X1304198Y126300I3202J1418D01*
G02X1304498Y127719I3502J1D01*
G03Y127881I-183J81D01*
G02X1304198Y129300I3202J1418D01*
G02X1304498Y130719I3502J1D01*
G03Y130881I-183J81D01*
G02X1304198Y132300I3202J1418D01*
G02X1304498Y133719I3502J1D01*
G03Y133881I-183J81D01*
G02X1304198Y135298I3202J1418D01*
G01Y135300D01*
G02X1307700Y138802I3502J0D01*
G01X1307702D01*
G02X1309119Y138502I-1J-3502D01*
G03X1309281I81J183D01*
G02X1310700Y138802I1418J-3202D01*
G02X1312119Y138502I1J-3502D01*
G03X1312281I81J183D01*
G02X1313700Y138802I1418J-3202D01*
G37*
G36*
G01X448738Y115902D02*
G02X450157Y115602I1J-3502D01*
G03X450319I81J183D01*
G02X451738Y115902I1418J-3202D01*
G02X453157Y115602I1J-3502D01*
G03X453319I81J183D01*
G02X454736Y115902I1418J-3202D01*
G01X454738D01*
G02X458240Y112400I0J-3502D01*
G01Y112398D01*
G02X457940Y110981I-3502J1D01*
G03Y110819I183J-81D01*
G02X458240Y109400I-3202J-1418D01*
G02X457940Y107981I-3502J-1D01*
G03Y107819I183J-81D01*
G02X458240Y106400I-3202J-1418D01*
G02X457940Y104981I-3502J-1D01*
G03Y104819I183J-81D01*
G02X458240Y103400I-3202J-1418D01*
G02X457940Y101981I-3502J-1D01*
G03Y101819I183J-81D01*
G02X458240Y100402I-3202J-1418D01*
G01Y100400D01*
G02X454738Y96898I-3502J0D01*
G01X454736D01*
G02X453319Y97198I1J3502D01*
G03X453157I-81J-183D01*
G02X451738Y96898I-1418J3202D01*
G02X450319Y97198I-1J3502D01*
G03X450157I-81J-183D01*
G02X448738Y96898I-1418J3202D01*
G02X447319Y97198I-1J3502D01*
G03X447157I-81J-183D01*
G02X445738Y96898I-1418J3202D01*
G02X444319Y97198I-1J3502D01*
G03X444157I-81J-183D01*
G02X442740Y96898I-1418J3202D01*
G01X442738D01*
G02X439236Y100400I0J3502D01*
G01Y100402D01*
G02X439536Y101819I3502J-1D01*
G03Y101981I-183J81D01*
G02X439236Y103400I3202J1418D01*
G02X439536Y104819I3502J1D01*
G03Y104981I-183J81D01*
G02X439236Y106400I3202J1418D01*
G02X439536Y107819I3502J1D01*
G03Y107981I-183J81D01*
G02X439236Y109400I3202J1418D01*
G02X439536Y110819I3502J1D01*
G03Y110981I-183J81D01*
G02X439236Y112398I3202J1418D01*
G01Y112400D01*
G02X442738Y115902I3502J0D01*
G01X442740D01*
G02X444157Y115602I-1J-3502D01*
G03X444319I81J183D01*
G02X445738Y115902I1418J-3202D01*
G02X447157Y115602I1J-3502D01*
G03X447319I81J183D01*
G02X448738Y115902I1418J-3202D01*
G37*
G36*
G01X1313700Y94402D02*
G02X1315119Y94102I1J-3502D01*
G03X1315281I81J183D01*
G02X1316700Y94402I1418J-3202D01*
G02X1318119Y94102I1J-3502D01*
G03X1318281I81J183D01*
G02X1319698Y94402I1418J-3202D01*
G01X1319700D01*
G02X1323202Y90900I0J-3502D01*
G01Y90898D01*
G02X1322902Y89481I-3502J1D01*
G03Y89319I183J-81D01*
G02X1323202Y87900I-3202J-1418D01*
G02X1322902Y86481I-3502J-1D01*
G03Y86319I183J-81D01*
G02X1323202Y84900I-3202J-1418D01*
G02X1322902Y83481I-3502J-1D01*
G03Y83319I183J-81D01*
G02X1323202Y81900I-3202J-1418D01*
G02X1322902Y80481I-3502J-1D01*
G03Y80319I183J-81D01*
G02X1323202Y78902I-3202J-1418D01*
G01Y78900D01*
G02X1319700Y75398I-3502J0D01*
G01X1319698D01*
G02X1318281Y75698I1J3502D01*
G03X1318119I-81J-183D01*
G02X1316700Y75398I-1418J3202D01*
G02X1315281Y75698I-1J3502D01*
G03X1315119I-81J-183D01*
G02X1313700Y75398I-1418J3202D01*
G02X1312281Y75698I-1J3502D01*
G03X1312119I-81J-183D01*
G02X1310700Y75398I-1418J3202D01*
G02X1309281Y75698I-1J3502D01*
G03X1309119I-81J-183D01*
G02X1307702Y75398I-1418J3202D01*
G01X1307700D01*
G02X1304198Y78900I0J3502D01*
G01Y78902D01*
G02X1304498Y80319I3502J-1D01*
G03Y80481I-183J81D01*
G02X1304198Y81900I3202J1418D01*
G02X1304498Y83319I3502J1D01*
G03Y83481I-183J81D01*
G02X1304198Y84900I3202J1418D01*
G02X1304498Y86319I3502J1D01*
G03Y86481I-183J81D01*
G02X1304198Y87900I3202J1418D01*
G02X1304498Y89319I3502J1D01*
G03Y89481I-183J81D01*
G02X1304198Y90898I3202J1418D01*
G01Y90900D01*
G02X1307700Y94402I3502J0D01*
G01X1307702D01*
G02X1309119Y94102I-1J-3502D01*
G03X1309281I81J183D01*
G02X1310700Y94402I1418J-3202D01*
G02X1312119Y94102I1J-3502D01*
G03X1312281I81J183D01*
G02X1313700Y94402I1418J-3202D01*
G37*
G36*
G01X448738Y71502D02*
G02X450157Y71202I1J-3502D01*
G03X450319I81J183D01*
G02X451738Y71502I1418J-3202D01*
G02X453157Y71202I1J-3502D01*
G03X453319I81J183D01*
G02X454736Y71502I1418J-3202D01*
G01X454738D01*
G02X458240Y68000I0J-3502D01*
G01Y67998D01*
G02X457940Y66581I-3502J1D01*
G03Y66419I183J-81D01*
G02X458240Y65000I-3202J-1418D01*
G02X457940Y63581I-3502J-1D01*
G03Y63419I183J-81D01*
G02X458240Y62000I-3202J-1418D01*
G02X457940Y60581I-3502J-1D01*
G03Y60419I183J-81D01*
G02X458240Y59000I-3202J-1418D01*
G02X457940Y57581I-3502J-1D01*
G03Y57419I183J-81D01*
G02X458240Y56002I-3202J-1418D01*
G01Y56000D01*
G02X454738Y52498I-3502J0D01*
G01X454736D01*
G02X453319Y52798I1J3502D01*
G03X453157I-81J-183D01*
G02X451738Y52498I-1418J3202D01*
G02X450319Y52798I-1J3502D01*
G03X450157I-81J-183D01*
G02X448738Y52498I-1418J3202D01*
G02X447319Y52798I-1J3502D01*
G03X447157I-81J-183D01*
G02X445738Y52498I-1418J3202D01*
G02X444319Y52798I-1J3502D01*
G03X444157I-81J-183D01*
G02X442740Y52498I-1418J3202D01*
G01X442738D01*
G02X439236Y56000I0J3502D01*
G01Y56002D01*
G02X439536Y57419I3502J-1D01*
G03Y57581I-183J81D01*
G02X439236Y59000I3202J1418D01*
G02X439536Y60419I3502J1D01*
G03Y60581I-183J81D01*
G02X439236Y62000I3202J1418D01*
G02X439536Y63419I3502J1D01*
G03Y63581I-183J81D01*
G02X439236Y65000I3202J1418D01*
G02X439536Y66419I3502J1D01*
G03Y66581I-183J81D01*
G02X439236Y67998I3202J1418D01*
G01Y68000D01*
G02X442738Y71502I3502J0D01*
G01X442740D01*
G02X444157Y71202I-1J-3502D01*
G03X444319I81J183D01*
G02X445738Y71502I1418J-3202D01*
G02X447157Y71202I1J-3502D01*
G03X447319I81J183D01*
G02X448738Y71502I1418J-3202D01*
G37*
G36*
G01X1406230Y24578D02*
G02X1407649Y24278I1J-3502D01*
G03X1407811I81J183D01*
G02X1409230Y24578I1418J-3202D01*
G02X1410649Y24278I1J-3502D01*
G03X1410811I81J183D01*
G02X1412228Y24578I1418J-3202D01*
G01X1412230D01*
G02X1415732Y21076I0J-3502D01*
G01Y21074D01*
G02X1415432Y19657I-3502J1D01*
G03Y19495I183J-81D01*
G02X1415732Y18076I-3202J-1418D01*
G02X1415432Y16657I-3502J-1D01*
G03Y16495I183J-81D01*
G02X1415732Y15078I-3202J-1418D01*
G01Y15076D01*
G02X1412230Y11574I-3502J0D01*
G01X1412228D01*
G02X1410811Y11874I1J3502D01*
G03X1410649I-81J-183D01*
G02X1409230Y11574I-1418J3202D01*
G02X1407811Y11874I-1J3502D01*
G03X1407649I-81J-183D01*
G02X1406230Y11574I-1418J3202D01*
G02X1404811Y11874I-1J3502D01*
G03X1404649I-81J-183D01*
G02X1403230Y11574I-1418J3202D01*
G02X1401811Y11874I-1J3502D01*
G03X1401649I-81J-183D01*
G02X1400230Y11574I-1418J3202D01*
G02X1398811Y11874I-1J3502D01*
G03X1398649I-81J-183D01*
G02X1397232Y11574I-1418J3202D01*
G01X1397230D01*
G02X1393728Y15076I0J3502D01*
G01Y15078D01*
G02X1394028Y16495I3502J-1D01*
G03Y16657I-183J81D01*
G02X1393728Y18076I3202J1418D01*
G02X1394028Y19495I3502J1D01*
G03Y19657I-183J81D01*
G02X1393728Y21074I3202J1418D01*
G01Y21076D01*
G02X1397230Y24578I3502J0D01*
G01X1397232D01*
G02X1398649Y24278I-1J-3502D01*
G03X1398811I81J183D01*
G02X1400230Y24578I1418J-3202D01*
G02X1401649Y24278I1J-3502D01*
G03X1401811I81J183D01*
G02X1403230Y24578I1418J-3202D01*
G02X1404649Y24278I1J-3502D01*
G03X1404811I81J183D01*
G02X1406230Y24578I1418J-3202D01*
G37*
G36*
G01X334500Y24502D02*
G02X335919Y24202I1J-3502D01*
G03X336081I81J183D01*
G02X337500Y24502I1418J-3202D01*
G02X338919Y24202I1J-3502D01*
G03X339081I81J183D01*
G02X340498Y24502I1418J-3202D01*
G01X340500D01*
G02X344002Y21000I0J-3502D01*
G01Y20998D01*
G02X343702Y19581I-3502J1D01*
G03Y19419I183J-81D01*
G02X344002Y18000I-3202J-1418D01*
G02X343702Y16581I-3502J-1D01*
G03Y16419I183J-81D01*
G02X344002Y15002I-3202J-1418D01*
G01Y15000D01*
G02X340500Y11498I-3502J0D01*
G01X340498D01*
G02X339081Y11798I1J3502D01*
G03X338919I-81J-183D01*
G02X337500Y11498I-1418J3202D01*
G02X336081Y11798I-1J3502D01*
G03X335919I-81J-183D01*
G02X334500Y11498I-1418J3202D01*
G02X333081Y11798I-1J3502D01*
G03X332919I-81J-183D01*
G02X331500Y11498I-1418J3202D01*
G02X330081Y11798I-1J3502D01*
G03X329919I-81J-183D01*
G02X328500Y11498I-1418J3202D01*
G02X327081Y11798I-1J3502D01*
G03X326919I-81J-183D01*
G02X325502Y11498I-1418J3202D01*
G01X325500D01*
G02X321998Y15000I0J3502D01*
G01Y15002D01*
G02X322298Y16419I3502J-1D01*
G03Y16581I-183J81D01*
G02X321998Y18000I3202J1418D01*
G02X322298Y19419I3502J1D01*
G03Y19581I-183J81D01*
G02X321998Y20998I3202J1418D01*
G01Y21000D01*
G02X325500Y24502I3502J0D01*
G01X325502D01*
G02X326919Y24202I-1J-3502D01*
G03X327081I81J183D01*
G02X328500Y24502I1418J-3202D01*
G02X329919Y24202I1J-3502D01*
G03X330081I81J183D01*
G02X331500Y24502I1418J-3202D01*
G02X332919Y24202I1J-3502D01*
G03X333081I81J183D01*
G02X334500Y24502I1418J-3202D01*
G37*
G36*
G01X1438098Y14529D02*
X1438089Y14470D01*
X1438139Y14362D01*
X1438551Y14105D01*
X1438670Y14107D01*
X1438719Y14141D01*
G02X1441417Y14976I2699J-3944D01*
G02Y5418I0J-4779D01*
G02X1436638Y10194I0J4779D01*
G01Y10200D01*
G02X1436639Y10227I4774J-163D01*
G01Y10228D01*
G03X1436520Y10411I-200J0D01*
G01X1436185Y10560D01*
G03X1435969Y10525I-81J-183D01*
G02X1438098Y14529I-4551J4988D01*
G37*
G36*
G01X247547D02*
X247538Y14470D01*
X247588Y14362D01*
X248000Y14105D01*
X248119Y14107D01*
X248168Y14141D01*
G02X250866Y14976I2699J-3944D01*
G01X250868D01*
G02X246088Y10197I-1J-4779D01*
G01Y10228D01*
G03X245969Y10411I-200J0D01*
G01X245634Y10560D01*
G03X245418Y10525I-81J-183D01*
G02X247547Y14529I-4551J4988D01*
G37*
G36*
G01X1225966Y319000D02*
X1275500D01*
G02X1276914Y318414I0J-1999D01*
G01X1279414Y315914D01*
G02X1280000Y314500I-1413J-1414D01*
G01Y51500D01*
G02X1279414Y50086I-1999J0D01*
G01X1276914Y47586D01*
G02X1275500Y47000I-1414J1413D01*
G01X1115567D01*
G02X1114153Y47586I0J1999D01*
G01X1099586Y62153D01*
G02X1099000Y63567I1413J1414D01*
G01Y106106D01*
G03X1098941Y106248I-200J0D01*
G01X1095248Y109941D01*
G03X1095106Y110000I-142J-141D01*
G01X910000D01*
G02X908586Y110586I0J1999D01*
G01X901586Y117586D01*
G02X901000Y119000I1413J1414D01*
G01Y185000D01*
G02X901586Y186414I1999J0D01*
G01X905086Y189914D01*
G02X906500Y190500I1414J-1413D01*
G01X956551D01*
G02X957965Y189914I0J-1999D01*
G01X981058Y166821D01*
G03X981200Y166762I142J141D01*
G01X985094D01*
G03X985279Y166886I0J200D01*
G01X985303Y166942D01*
X985279Y167060D01*
X970074Y182265D01*
G02X969488Y183679I1413J1414D01*
G01Y200875D01*
G02X970074Y202289I1999J0D01*
G01X972219Y204434D01*
G02X973633Y205020I1414J-1413D01*
G01X1013854D01*
G02X1015268Y204434I0J-1999D01*
G01X1017914Y201788D01*
G02X1018500Y200374I-1413J-1414D01*
G01Y180012D01*
G03X1018559Y179870I200J0D01*
G01X1020714Y177714D01*
G02X1020843Y177573I-1409J-1419D01*
G03X1020997Y177500I154J127D01*
G01X1054589D01*
G03X1054731Y177559I0J200D01*
G01X1109786Y232614D01*
G02X1111200Y233200I1414J-1413D01*
G01X1154289D01*
G03X1154431Y233259I0J200D01*
G01X1166141Y244969D01*
G03X1166200Y245111I-141J142D01*
G01Y258700D01*
G02X1166786Y260114I1999J0D01*
G01X1171646Y264974D01*
G03X1171695Y265177I-141J141D01*
G01X1171568Y265570D01*
X1171483Y265643D01*
X1171427Y265652D01*
G02X1168484Y269110I560J3458D01*
G02X1169696Y271760I3503J0D01*
G03X1169765Y271911I-131J151D01*
G01Y272215D01*
G03X1169696Y272366I-200J0D01*
G02X1168484Y275016I2291J2650D01*
G02X1175488I3502J0D01*
G02X1174276Y272366I-3503J0D01*
G03X1174207Y272215I131J-151D01*
G01Y271911D01*
G03X1174276Y271760I200J0D01*
G02X1175488Y269110I-2291J-2650D01*
G01Y269105D01*
G02X1175191Y267696I-3503J2D01*
G01X1175170Y267649D01*
X1175178Y267549D01*
X1175389Y267226D01*
G03X1175556Y267135I168J109D01*
G01X1184429D01*
G03X1184606Y267241I0J200D01*
G02X1190794I3094J-1642D01*
G03X1190971Y267135I177J94D01*
G01X1195493D01*
G03X1195688Y267290I0J200D01*
G02X1196013Y268153I3411J-792D01*
G03Y268343I-176J95D01*
G02X1195596Y270000I3087J1658D01*
G02X1196011Y271654I3504J0D01*
G03X1196010Y271842I-177J93D01*
G02X1195594Y273500I3091J1657D01*
G02X1196010Y275156I3506J0D01*
G03Y275344I-177J94D01*
G02X1195594Y277000I3090J1656D01*
G02X1202606I3506J0D01*
G02X1202190Y275344I-3506J0D01*
G03Y275156I177J-94D01*
G02X1202606Y273500I-3090J-1656D01*
G02X1202190Y271842I-3507J-1D01*
G03X1202189Y271654I176J-95D01*
G02X1202604Y270000I-3089J-1654D01*
G02X1202187Y268343I-3504J1D01*
G03Y268153I176J-95D01*
G02X1202512Y267290I-3086J-1655D01*
G03X1202707Y267135I195J45D01*
G01X1207229D01*
G03X1207406Y267241I0J200D01*
G02X1213594I3094J-1642D01*
G03X1213771Y267135I177J94D01*
G01X1218807D01*
G03X1218949Y267194I0J200D01*
G01X1221256Y269501D01*
G03X1221315Y269643I-141J142D01*
G01Y314349D01*
G02X1221901Y315763I1999J0D01*
G01X1224552Y318414D01*
G02X1225966Y319000I1414J-1413D01*
G37*
G36*
G01X486100D02*
X536375D01*
G02X537789Y318414I0J-1999D01*
G01X540259Y315944D01*
G02X540845Y314530I-1413J-1414D01*
G01Y269824D01*
G03X540904Y269682I200J0D01*
G01X543508Y267078D01*
G03X543650Y267019I142J141D01*
G01X548100D01*
G03X548280Y267132I0J200D01*
G02X554580I3150J-1533D01*
G03X554760Y267019I180J87D01*
G01X559271D01*
X559381Y267109D01*
X559395Y267180D01*
G02X559743Y268153I3435J-680D01*
G03Y268343I-176J95D01*
G02X559326Y270000I3087J1658D01*
G02X559741Y271654I3504J0D01*
G03X559740Y271842I-177J93D01*
G02X559324Y273500I3091J1657D01*
G02X559740Y275156I3506J0D01*
G03Y275344I-177J94D01*
G02X559324Y277000I3090J1656D01*
G02X566336I3506J0D01*
G02X565920Y275344I-3506J0D01*
G03Y275156I177J-94D01*
G02X566336Y273500I-3090J-1656D01*
G02X565920Y271842I-3507J-1D01*
G03X565919Y271654I176J-95D01*
G02X566334Y270000I-3089J-1654D01*
G02X565917Y268343I-3504J1D01*
G03Y268153I176J-95D01*
G02X566265Y267180I-3087J-1653D01*
G01X566279Y267109D01*
X566389Y267019D01*
X573137D01*
G03X573317Y267132I0J200D01*
G02X579617I3150J-1533D01*
G03X579797Y267019I180J87D01*
G01X585308D01*
G02X586722Y266433I0J-1999D01*
G01X633104Y220051D01*
G03X633246Y219992I142J141D01*
G01X691383D01*
G02X692797Y219406I0J-1999D01*
G01X695517Y216686D01*
G02X696103Y215272I-1413J-1414D01*
G01Y210343D01*
G02X695517Y208929I-1999J0D01*
G01X686376Y199788D01*
G02X684962Y199202I-1414J1413D01*
G01X680373D01*
G03X680231Y199143I0J-200D01*
G01X679912Y198824D01*
G03X679853Y198682I141J-142D01*
G01Y172448D01*
G03X679912Y172306I200J0D01*
G01X685477Y166741D01*
G03X685619Y166682I142J141D01*
G01X730158D01*
G03X730348Y166819I0J200D01*
G01X730468Y167179D01*
G03X730399Y167402I-190J63D01*
G01X730398D01*
G02X730186Y167586I1201J1598D01*
G01X715686Y182086D01*
G02X715100Y183500I1413J1414D01*
G01Y200374D01*
G02X715686Y201788I1999J0D01*
G01X718332Y204434D01*
G02X719746Y205020I1414J-1413D01*
G01X759967D01*
G02X761381Y204434I0J-1999D01*
G01X763526Y202289D01*
G02X764112Y200875I-1413J-1414D01*
G01Y183679D01*
G02X763526Y182265I-1999J0D01*
G01X748847Y167586D01*
G02X748635Y167402I-1413J1414D01*
G01X748634D01*
G03X748565Y167179I121J-160D01*
G01X748685Y166819D01*
G03X748875Y166682I190J63D01*
G01X754000D01*
G03X754142Y166741I0J200D01*
G01X777315Y189914D01*
G02X778729Y190500I1414J-1413D01*
G01X827100D01*
G02X828514Y189914I0J-1999D01*
G01X832014Y186414D01*
G02X832600Y185000I-1413J-1414D01*
G01Y119000D01*
G02X832014Y117586I-1999J0D01*
G01X825014Y110586D01*
G02X823600Y110000I-1414J1413D01*
G01X638494D01*
G03X638352Y109941I0J-200D01*
G01X634659Y106248D01*
G03X634600Y106106I141J-142D01*
G01Y63567D01*
G02X634014Y62153I-1999J0D01*
G01X619447Y47586D01*
G02X618033Y47000I-1414J1413D01*
G01X486100D01*
G02X484686Y47586I0J1999D01*
G01X482186Y50086D01*
G02X481600Y51500I1413J1414D01*
G01Y314500D01*
G02X482186Y315914I1999J0D01*
G01X484686Y318414D01*
G02X486100Y319000I1414J-1413D01*
G37*
G36*
G01X704934Y286534D02*
G02X706684Y287002I1749J-3034D01*
G02Y279998I0J-3502D01*
G02X704934Y280466I-1J3502D01*
G03X704734I-100J-173D01*
G02X702984Y279998I-1749J3034D01*
G02Y287002I0J3502D01*
G02X704734Y286534I1J-3502D01*
G03X704934I100J173D01*
G37*
G54D57*
X243785Y200472D03*
X166785D03*
X243785Y280472D03*
X166785D03*
X243785Y360472D03*
X166785D03*
X243785Y440472D03*
X166785D03*
X243785Y520472D03*
X166785D03*
X1565500Y200472D03*
X1488500D03*
X1565500Y280472D03*
X1488500D03*
X1565500Y360472D03*
X1488500D03*
X1565500Y440472D03*
X1488500D03*
X1565500Y520472D03*
X1488500D03*
G54D56*
X1034360Y254000D03*
X725000Y292500D03*
X1320346Y289900D03*
Y245500D03*
X1332671Y190644D03*
X1334140Y146642D03*
X1320346Y112300D03*
Y67900D03*
X1173500Y298500D03*
X1024600Y185000D03*
X704240D03*
X632186Y338917D03*
X623500Y379000D03*
X441938Y309700D03*
Y265300D03*
Y220900D03*
Y176500D03*
Y132100D03*
Y87700D03*
X438100Y214500D03*
X430608Y211389D03*
X438100Y170000D03*
X428277Y167056D03*
G54D59*
X1451417Y10197D03*
X260866D03*
G54D60*
X940197Y200984D03*
X822087D03*
G54D58*
X1565500Y550000D03*
Y470000D03*
Y390000D03*
Y310000D03*
Y230000D03*
X1488500Y550000D03*
Y470000D03*
Y390000D03*
Y310000D03*
Y230000D03*
X243785Y550000D03*
Y470000D03*
Y390000D03*
Y310000D03*
Y230000D03*
X166785Y550000D03*
Y470000D03*
Y390000D03*
Y310000D03*
Y230000D03*
G54D55*
X263780Y659961D03*
X1444882D03*
G54D51*
X1851457Y220433D03*
X1856772Y360433D03*
G54D54*
X300866Y10197D03*
X1491417D03*
G54D52*
X1212478Y300181D03*
X1529100Y78500D03*
X231600Y81000D03*
X19685Y766166D03*
X1854331D03*
G54D50*
X940197Y313484D03*
X822087Y88484D03*
Y313484D03*
X940197Y88484D03*
G54D53*
X1673228Y236614D03*
Y411614D03*
X59055Y236614D03*
Y411594D03*
%LPC*%
G75*
G36*
G01X486511Y180500D02*
X555989D01*
G02X556131Y180441I0J-200D01*
G01X559541Y177031D01*
G02X559600Y176889I-141J-142D01*
G01Y164044D01*
G02X559495Y163867I-200J-1D01*
G03X557653Y160784I1659J-3083D01*
G03X557709Y160159I3502J-1D01*
G01X557718Y160110D01*
X557689Y160017D01*
X557131Y159459D01*
G02X556989Y159400I-142J141D01*
G01X547900D01*
G03X546486Y158814I0J-1999D01*
G01X542086Y154414D01*
G03X541500Y153000I1413J-1414D01*
G01Y133200D01*
G03X542086Y131786I1999J0D01*
G01X543266Y130606D01*
G03X544680Y130020I1414J1413D01*
G01X548775D01*
G02X548919Y129959I0J-200D01*
G03X553941I2511J2441D01*
G02X554085Y130020I144J-139D01*
G01X557169D01*
G02X557311Y129961I0J-200D01*
G01X559541Y127731D01*
G02X559600Y127589I-141J-142D01*
G01Y119287D01*
X559595Y119265D01*
G03X559505Y118477I3412J-789D01*
G03X559595Y117689I3502J1D01*
G01X559600Y117667D01*
Y114933D01*
X559595Y114911D01*
G03X559505Y114123I3412J-789D01*
G03X559595Y113335I3502J1D01*
G01X559600Y113313D01*
Y52911D01*
G02X559541Y52769I-200J0D01*
G01X557831Y51059D01*
G02X557689Y51000I-142J141D01*
G01X487011D01*
G02X486869Y51059I0J200D01*
G01X485659Y52269D01*
G02X485600Y52411I141J142D01*
G01Y179589D01*
G02X485659Y179731I200J0D01*
G01X486369Y180441D01*
G02X486511Y180500I142J-141D01*
G37*
G36*
G01X487011Y315000D02*
X535464D01*
G02X535606Y314941I0J-200D01*
G01X536786Y313761D01*
G02X536845Y313619I-141J-142D01*
G01Y268913D01*
G03X537431Y267499I1999J0D01*
G01X541325Y263605D01*
G03X542739Y263019I1414J1413D01*
G01X548986D01*
G02X549118Y262969I0J-200D01*
G03X551430Y262098I2311J2631D01*
G03X553742Y262969I1J3502D01*
G02X553874Y263019I132J-150D01*
G01X559400D01*
G02X559600Y262819I0J-200D01*
G01Y252487D01*
X559595Y252465D01*
G03X559505Y251677I3412J-789D01*
G03X559595Y250889I3502J1D01*
G01X559600Y250867D01*
Y248133D01*
X559595Y248111D01*
G03X559505Y247323I3412J-789D01*
G03X559595Y246535I3502J1D01*
G01X559600Y246513D01*
Y187911D01*
G02X559541Y187769I-200J0D01*
G01X556331Y184559D01*
G02X556189Y184500I-142J141D01*
G01X486511D01*
G02X486369Y184559I0J200D01*
G01X485659Y185269D01*
G02X485600Y185411I141J142D01*
G01Y313589D01*
G02X485659Y313731I200J0D01*
G01X486869Y314941D01*
G02X487011Y315000I142J-141D01*
G37*
G36*
G01X578911Y263019D02*
X584397D01*
G02X584539Y262960I0J-200D01*
G01X630921Y216578D01*
G03X632335Y215992I1414J1413D01*
G01X690472D01*
G02X690614Y215933I0J-200D01*
G01X692044Y214503D01*
G02X692103Y214361I-141J-142D01*
G01Y211254D01*
G02X692044Y211112I-200J0D01*
G01X684193Y203261D01*
G02X684051Y203202I-142J141D01*
G01X679462D01*
G03X678048Y202616I0J-1999D01*
G01X676439Y201007D01*
G03X675853Y199593I1413J-1414D01*
G01Y171537D01*
G03X676439Y170123I1999J0D01*
G01X683294Y163268D01*
G03X684708Y162682I1414J1413D01*
G01X754911D01*
G03X756325Y163268I0J1999D01*
G01X779498Y186441D01*
G02X779640Y186500I142J-141D01*
G01X826189D01*
G02X826331Y186441I0J-200D01*
G01X828541Y184231D01*
G02X828600Y184089I-141J-142D01*
G01Y119911D01*
G02X828541Y119769I-200J0D01*
G01X822831Y114059D01*
G02X822689Y114000I-142J141D01*
G01X637583D01*
G03X636169Y113414I0J-1999D01*
G01X631186Y108431D01*
G03X630600Y107017I1413J-1414D01*
G01Y64478D01*
G02X630541Y64336I-200J0D01*
G01X617264Y51059D01*
G02X617122Y51000I-142J141D01*
G01X565511D01*
G02X565369Y51059I0J200D01*
G01X563659Y52769D01*
G02X563600Y52911I141J142D01*
G01Y110578D01*
X563688Y110687D01*
X563757Y110702D01*
G03X566509Y114123I-750J3421D01*
G03X565839Y116182I-3501J-1D01*
G02Y116418I162J118D01*
G03X566509Y118477I-2831J2060D01*
G03X563757Y121898I-3502J0D01*
G01X563688Y121913D01*
X563600Y122022D01*
Y127789D01*
G02X563659Y127931I200J0D01*
G01X565689Y129961D01*
G02X565831Y130020I142J-141D01*
G01X571575D01*
G02X571719Y129959I0J-200D01*
G03X576741I2511J2441D01*
G02X576885Y130020I144J-139D01*
G01X580120D01*
G03X581534Y130606I0J1999D01*
G01X583514Y132586D01*
G03X584100Y134000I-1413J1414D01*
G01Y151100D01*
G03X583514Y152514I-1999J0D01*
G01X577214Y158814D01*
G03X575800Y159400I-1414J-1413D01*
G01X568081D01*
G02X567923Y159478I0J200D01*
G01X567700Y159766D01*
X567682Y159855D01*
X567694Y159901D01*
G03X567807Y160783I-3389J882D01*
G01Y160784D01*
G03X564305Y164286I-3502J0D01*
G03X564031Y164275I3J-3502D01*
G01X563989Y164272D01*
X563911Y164299D01*
X563664Y164528D01*
G02X563600Y164674I136J147D01*
G01Y243778D01*
X563688Y243887D01*
X563757Y243902D01*
G03X566509Y247323I-750J3421D01*
G03X565839Y249382I-3501J-1D01*
G02Y249618I162J118D01*
G03X566509Y251677I-2831J2060D01*
G03X563757Y255098I-3502J0D01*
G01X563688Y255113D01*
X563600Y255222D01*
Y262819D01*
G02X563800Y263019I200J0D01*
G01X574023D01*
X574155Y262969D01*
G03X578779I2312J2631D01*
G01X578911Y263019D01*
G37*
G36*
G01X719159Y199605D02*
X720515Y200961D01*
G02X720657Y201020I142J-141D01*
G01X759056D01*
G02X759198Y200961I0J-200D01*
G01X760053Y200106D01*
G02X760112Y199964I-141J-142D01*
G01Y184590D01*
G02X760053Y184448I-200J0D01*
G01X746664Y171059D01*
G02X746522Y171000I-142J141D01*
G01X732511D01*
G02X732369Y171059I0J200D01*
G01X719159Y184269D01*
G02X719100Y184411I141J142D01*
G01Y199463D01*
G02X719159Y199605I200J0D01*
G37*
G36*
G01X1190270Y263135D02*
X1195354D01*
G02X1195496Y263076I0J-200D01*
G01X1197941Y260631D01*
G02X1198000Y260489I-141J-142D01*
G01Y255072D01*
G02X1197880Y254888I-200J-1D01*
G03X1195775Y251677I1397J-3211D01*
G03X1196445Y249618I3502J1D01*
G02Y249382I-162J-118D01*
G03X1195775Y247323I2832J-2060D01*
G03X1197880Y244112I3502J0D01*
G02X1198000Y243928I-80J-183D01*
G01Y165611D01*
G02X1197941Y165469I-200J0D01*
G01X1195917Y163445D01*
X1195887Y163430D01*
G03X1194279Y161822I1538J-3146D01*
G02X1194241Y161769I-179J89D01*
G01X1194031Y161559D01*
G02X1193889Y161500I-142J141D01*
G01X1183800D01*
G03X1182386Y160914I0J-1999D01*
G01X1176414Y154942D01*
G03X1175828Y153528I1413J-1414D01*
G01Y132192D01*
G03X1176414Y130778I1999J0D01*
G01X1176795Y130397D01*
G03X1178209Y129811I1414J1413D01*
G01X1185266D01*
G02X1185397Y129762I0J-200D01*
G03X1190003I2303J2637D01*
G02X1190134Y129811I131J-151D01*
G01X1196878D01*
G02X1197020Y129752I0J-200D01*
G01X1197941Y128831D01*
G02X1198000Y128689I-141J-142D01*
G01Y121872D01*
G02X1197880Y121688I-200J-1D01*
G03X1195775Y118477I1397J-3211D01*
G03X1196445Y116418I3502J1D01*
G02Y116182I-162J-118D01*
G03X1195775Y114123I2832J-2060D01*
G03X1197880Y110912I3502J0D01*
G02X1198000Y110728I-80J-183D01*
G01Y52911D01*
G02X1197941Y52769I-200J0D01*
G01X1196231Y51059D01*
G02X1196089Y51000I-142J141D01*
G01X1116478D01*
G02X1116336Y51059I0J200D01*
G01X1103059Y64336D01*
G02X1103000Y64478I141J142D01*
G01Y107017D01*
G03X1102414Y108431I-1999J0D01*
G01X1097431Y113414D01*
G03X1096017Y114000I-1414J-1413D01*
G01X910911D01*
G02X910769Y114059I0J200D01*
G01X905059Y119769D01*
G02X905000Y119911I141J142D01*
G01Y184089D01*
G02X905059Y184231I200J0D01*
G01X907269Y186441D01*
G02X907411Y186500I142J-141D01*
G01X955640D01*
G02X955782Y186441I0J-200D01*
G01X978875Y163348D01*
G03X980289Y162762I1414J1413D01*
G01X1007447D01*
G03X1008861Y163348I0J1999D01*
G01X1018954Y173441D01*
G02X1019096Y173500I142J-141D01*
G01X1055500D01*
G03X1056914Y174086I0J1999D01*
G01X1111969Y229141D01*
G02X1112111Y229200I142J-141D01*
G01X1155200D01*
G03X1156614Y229786I0J1999D01*
G01X1169614Y242786D01*
G03X1170200Y244200I-1413J1414D01*
G01Y257789D01*
G02X1170259Y257931I200J0D01*
G01X1175404Y263076D01*
G02X1175546Y263135I142J-141D01*
G01X1185130D01*
G02X1185269Y263079I0J-200D01*
G03X1190131I2431J2522D01*
G02X1190270Y263135I139J-144D01*
G37*
G36*
G01X973547Y200106D02*
X974402Y200961D01*
G02X974544Y201020I142J-141D01*
G01X1012943D01*
G02X1013085Y200961I0J-200D01*
G01X1014441Y199605D01*
G02X1014500Y199463I-141J-142D01*
G01Y184411D01*
G02X1014441Y184269I-200J0D01*
G01X1001231Y171059D01*
G02X1001089Y171000I-142J141D01*
G01X987078D01*
G02X986936Y171059I0J200D01*
G01X973547Y184448D01*
G02X973488Y184590I141J142D01*
G01Y199964D01*
G02X973547Y200106I200J0D01*
G37*
G36*
G01X1204711Y180500D02*
X1275089D01*
G02X1275231Y180441I0J-200D01*
G01X1275941Y179731D01*
G02X1276000Y179589I-141J-142D01*
G01Y52411D01*
G02X1275941Y52269I-200J0D01*
G01X1274731Y51059D01*
G02X1274589Y51000I-142J141D01*
G01X1203911D01*
G02X1203769Y51059I0J200D01*
G01X1202059Y52769D01*
G02X1202000Y52911I141J142D01*
G01Y111851D01*
G02X1202042Y111974I200J0D01*
G03X1202779Y114123I-2765J2149D01*
G03X1202109Y116182I-3502J-1D01*
G02Y116418I162J118D01*
G03X1202779Y118477I-2832J2060D01*
G03X1202042Y120626I-3502J0D01*
G02X1202000Y120749I158J123D01*
G01Y128789D01*
G02X1202059Y128931I200J0D01*
G01X1202880Y129752D01*
G02X1203022Y129811I142J-141D01*
G01X1208066D01*
G02X1208197Y129762I0J-200D01*
G03X1212803I2303J2637D01*
G02X1212934Y129811I131J-151D01*
G01X1219382D01*
G03X1220796Y130397I0J1999D01*
G01X1224817Y134418D01*
G03X1225403Y135832I-1413J1414D01*
G01Y153697D01*
G03X1224817Y155111I-1999J0D01*
G01X1219014Y160914D01*
G03X1217600Y161500I-1414J-1413D01*
G01X1204111D01*
G02X1203969Y161559I0J200D01*
G01X1203736Y161792D01*
X1203721Y161822D01*
G03X1202113Y163430I-3146J-1538D01*
G01X1202083Y163445D01*
X1202059Y163469D01*
G02X1202000Y163611I141J142D01*
G01Y177789D01*
G02X1202059Y177931I200J0D01*
G01X1204569Y180441D01*
G02X1204711Y180500I142J-141D01*
G37*
G36*
G01X1226877Y315000D02*
X1274589D01*
G02X1274731Y314941I0J-200D01*
G01X1275941Y313731D01*
G02X1276000Y313589I-141J-142D01*
G01Y185411D01*
G02X1275941Y185269I-200J0D01*
G01X1275231Y184559D01*
G02X1275089Y184500I-142J141D01*
G01X1204311D01*
G02X1204169Y184559I0J200D01*
G01X1202059Y186669D01*
G02X1202000Y186811I141J142D01*
G01Y245051D01*
G02X1202042Y245174I200J0D01*
G03X1202779Y247323I-2765J2149D01*
G03X1202109Y249382I-3502J-1D01*
G02Y249618I162J118D01*
G03X1202779Y251677I-2832J2060D01*
G03X1202042Y253826I-3502J0D01*
G02X1202000Y253949I158J123D01*
G01Y260289D01*
G02X1202059Y260431I200J0D01*
G01X1204704Y263076D01*
G02X1204846Y263135I142J-141D01*
G01X1207930D01*
G02X1208069Y263079I0J-200D01*
G03X1212931I2431J2522D01*
G02X1213070Y263135I139J-144D01*
G01X1219718D01*
G03X1221132Y263721I0J1999D01*
G01X1224729Y267318D01*
G03X1225315Y268732I-1413J1414D01*
G01Y313438D01*
G02X1225374Y313580I200J0D01*
G01X1226735Y314941D01*
G02X1226877Y315000I142J-141D01*
G37*
%LPD*%
G75*
G36*
G01X595663Y243193D02*
G03X595740Y243199I23J199D01*
G02X596708Y243336I970J-3366D01*
G02Y236330I0J-3503D01*
G02X596329Y236351I4J3503D01*
G03X596251Y236345I-24J-199D01*
G02X595276Y236206I-977J3365D01*
G02X594263Y236356I1J3504D01*
G03X594178Y236363I-59J-191D01*
G02X593708Y236330I-480J3469D01*
G02X593460Y236338I-11J3503D01*
G03X593429I-16J-199D01*
G02X592476Y236206I-953J3372D01*
G02Y243214I0J3504D01*
G02X592747Y243203I-6J-3504D01*
G03X592774Y243209I-30J198D01*
G02X593707Y243336I935J-3376D01*
G01X593708D01*
G02X594713Y243188I-2J-3503D01*
G03X594798Y243181I59J191D01*
G02X595276Y243214I480J-3471D01*
G02X595663Y243193I4J-3503D01*
G37*
G36*
G01X41338Y17716D02*
G03X53150I5906J0D01*
G01Y23763D01*
G02X55572Y32155I15747J1D01*
G03X38916I-8328J5246D01*
G02X41338Y23763I-13327J-8392D01*
G01Y17716D01*
G37*
G36*
G01Y330708D02*
G03X53150I5906J0D01*
G01Y336755D01*
G02X55572Y345147I15747J1D01*
G03X38916I-8328J5246D01*
G02X41338Y336755I-13327J-8392D01*
G01Y330708D01*
G37*
G36*
G01X273622Y53148D02*
G03X285434I5906J0D01*
G01Y59195D01*
G02X287856Y67587I15747J1D01*
G03X271200I-8328J5246D01*
G02X273622Y59195I-13327J-8392D01*
G01Y53148D01*
G37*
G36*
G01X309055Y561023D02*
G03X320867I5906J0D01*
G01Y567070D01*
G02X323289Y575462I15747J1D01*
G03X306633I-8328J5246D01*
G02X309055Y567070I-13327J-8392D01*
G01Y561023D01*
G37*
G36*
G01X387796Y344488D02*
G03X399608I5906J0D01*
G01Y350535D01*
G02X402030Y358927I15747J1D01*
G03X385374I-8328J5246D01*
G02X387796Y350535I-13327J-8392D01*
G01Y344488D01*
G37*
G36*
G01X742126Y64961D02*
G03X753938I5906J0D01*
G01Y71008D01*
G02X756360Y79400I15747J1D01*
G03X739704I-8328J5246D01*
G02X742126Y71008I-13327J-8392D01*
G01Y64961D01*
G37*
G36*
G01Y344488D02*
G03X753938I5906J0D01*
G01Y350535D01*
G02X756360Y358927I15747J1D01*
G03X739704I-8328J5246D01*
G02X742126Y350535I-13327J-8392D01*
G01Y344488D01*
G37*
G36*
G01X978346Y64961D02*
G03X990158I5906J0D01*
G01Y71008D01*
G02X992580Y79400I15747J1D01*
G03X975924I-8328J5246D01*
G02X978346Y71008I-13327J-8392D01*
G01Y64961D01*
G37*
G36*
G01Y344488D02*
G03X990158I5906J0D01*
G01Y350535D01*
G02X992580Y358927I15747J1D01*
G03X975924I-8328J5246D01*
G02X978346Y350535I-13327J-8392D01*
G01Y344488D01*
G37*
G36*
G01X1332678D02*
G03X1344490I5906J0D01*
G01Y350535D01*
G02X1346912Y358927I15747J1D01*
G03X1330256I-8328J5246D01*
G02X1332678Y350535I-13327J-8392D01*
G01Y344488D01*
G37*
G36*
G01X1411418Y561023D02*
G03X1423230I5906J0D01*
G01Y567070D01*
G02X1425652Y575462I15747J1D01*
G03X1408996I-8328J5246D01*
G02X1411418Y567070I-13327J-8392D01*
G01Y561023D01*
G37*
G36*
G01X1446850Y53149D02*
G03X1458662I5906J0D01*
G01Y59196D01*
G02X1461084Y67588I15747J1D01*
G03X1444428I-8328J5246D01*
G02X1446850Y59196I-13327J-8392D01*
G01Y53149D01*
G37*
G36*
G01X1679134Y17716D02*
G03X1690946I5906J0D01*
G01Y23763D01*
G02X1693368Y32155I15747J1D01*
G03X1676712I-8328J5246D01*
G02X1679134Y23763I-13327J-8392D01*
G01Y17716D01*
G37*
G36*
G01Y330708D02*
G03X1690946I5906J0D01*
G01Y336755D01*
G02X1693368Y345147I15747J1D01*
G03X1676712I-8328J5246D01*
G02X1679134Y336755I-13327J-8392D01*
G01Y330708D01*
G37*
G36*
G01X1793306Y96457D02*
G03X1805118I5906J0D01*
G01Y102504D01*
G02X1807540Y110896I15747J1D01*
G03X1790884I-8328J5246D01*
G02X1793306Y102504I-13327J-8392D01*
G01Y96457D01*
G37*
G36*
G01Y478346D02*
G03X1805118I5906J0D01*
G01Y484393D01*
G02X1807540Y492785I15747J1D01*
G03X1790884I-8328J5246D01*
G02X1793306Y484393I-13327J-8392D01*
G01Y478346D01*
G37*
G54D17*
X134600Y150000D03*
Y134000D03*
X156785Y101285D03*
X187600Y106500D03*
X176785Y102000D03*
X211425Y106075D03*
X210925Y115575D03*
X317000Y58000D03*
Y74475D03*
Y64500D03*
X325500Y15000D03*
Y18000D03*
Y21000D03*
X340500D03*
Y18000D03*
Y15000D03*
X337500Y21000D03*
Y18000D03*
Y15000D03*
X334500Y21000D03*
Y18000D03*
Y15000D03*
X331500Y21000D03*
Y18000D03*
Y15000D03*
X328500Y21000D03*
Y18000D03*
Y15000D03*
X321500Y74475D03*
Y66500D03*
X325100Y64000D03*
X332500Y63300D03*
X330500Y74476D03*
X326000D03*
X396216Y46875D03*
X428277Y167056D03*
X438100Y170000D03*
X430608Y211389D03*
X438100Y214500D03*
X454738Y56000D03*
X451738D03*
X448738D03*
X445738D03*
X442738D03*
X454738Y68000D03*
Y65000D03*
Y62000D03*
Y59000D03*
X451738D03*
Y62000D03*
Y65000D03*
Y68000D03*
X448738Y59000D03*
Y62000D03*
Y65000D03*
Y68000D03*
X445738Y59000D03*
Y62000D03*
Y65000D03*
Y68000D03*
X442738Y59000D03*
Y62000D03*
Y65000D03*
Y68000D03*
X441938Y87700D03*
X454738Y112400D03*
Y109400D03*
Y106400D03*
Y103400D03*
X451738D03*
Y106400D03*
Y109400D03*
Y112400D03*
X448738Y103400D03*
Y106400D03*
Y109400D03*
Y112400D03*
X445738Y103400D03*
Y106400D03*
Y109400D03*
Y112400D03*
X442738Y103400D03*
Y106400D03*
Y109400D03*
Y112400D03*
X454738Y100400D03*
X451738D03*
X448738D03*
X445738D03*
X442738D03*
X454738Y147800D03*
X451738D03*
X448738D03*
X445738D03*
X442738D03*
X454738Y144800D03*
X451738D03*
X448738D03*
X445738D03*
X442738D03*
X441938Y132100D03*
X454738Y156800D03*
Y153800D03*
Y150800D03*
X451738D03*
Y153800D03*
Y156800D03*
X448738Y150800D03*
Y153800D03*
Y156800D03*
X445738Y150800D03*
Y153800D03*
Y156800D03*
X442738Y150800D03*
Y153800D03*
Y156800D03*
X441938Y176500D03*
X454738Y201200D03*
Y198200D03*
Y195200D03*
Y192200D03*
X451738D03*
Y195200D03*
Y198200D03*
Y201200D03*
X448738Y192200D03*
Y195200D03*
Y198200D03*
Y201200D03*
X445738Y192200D03*
Y195200D03*
Y198200D03*
Y201200D03*
X442738Y192200D03*
Y195200D03*
Y198200D03*
Y201200D03*
X454738Y189200D03*
X451738D03*
X448738D03*
X445738D03*
X442738D03*
X454738Y239600D03*
Y236600D03*
X451738D03*
Y239600D03*
X448738Y236600D03*
Y239600D03*
X445738Y236600D03*
Y239600D03*
X442738Y236600D03*
Y239600D03*
X454738Y233600D03*
X451738D03*
X448738D03*
X445738D03*
X442738D03*
X441938Y220900D03*
X454738Y245600D03*
Y242600D03*
X451738D03*
Y245600D03*
X448738Y242600D03*
Y245600D03*
X445738Y242600D03*
Y245600D03*
X442738Y242600D03*
Y245600D03*
X441938Y265300D03*
X448738Y278000D03*
X451738D03*
X454738D03*
X448738Y290000D03*
Y287000D03*
Y284000D03*
Y281000D03*
X451738Y290000D03*
Y287000D03*
Y284000D03*
Y281000D03*
X454738D03*
Y284000D03*
Y287000D03*
Y290000D03*
X445738D03*
Y287000D03*
Y284000D03*
Y281000D03*
Y278000D03*
X442738Y290000D03*
Y287000D03*
Y284000D03*
Y281000D03*
Y278000D03*
X441938Y309700D03*
X517409Y322000D03*
X506309Y329000D03*
Y322000D03*
X517410Y329000D03*
X551430Y132400D03*
X561155Y160784D03*
X551430Y265600D03*
X563007Y118477D03*
Y114123D03*
X562830Y133300D03*
Y136800D03*
Y140300D03*
Y143800D03*
X574230Y132400D03*
X564305Y160784D03*
X563007Y251677D03*
X576467Y265600D03*
X563007Y247323D03*
X562830Y270000D03*
Y266500D03*
X590298Y282890D03*
X562830Y277000D03*
X571325Y292757D03*
X590298Y276984D03*
X562830Y273500D03*
X571542Y289065D03*
X565091Y302592D03*
X570443Y302702D03*
X595276Y239710D03*
X592476D03*
X620600Y239161D03*
X605800Y256500D03*
X609637Y254523D03*
X605700Y259500D03*
X616184Y267000D03*
X604684D03*
X612684Y297000D03*
X616684Y294500D03*
X602928Y293969D03*
X606084Y293100D03*
X600875Y295937D03*
X616184Y276000D03*
X604684D03*
Y285000D03*
X616184D03*
X590684Y313800D03*
Y310800D03*
X616684Y307975D03*
X622184Y308000D03*
X608259Y305000D03*
X618500Y333500D03*
X639010Y236377D03*
X640684Y264500D03*
Y269000D03*
X645900Y242200D03*
X644502Y246839D03*
X649200Y254500D03*
X650100Y251500D03*
X623684Y281000D03*
X637684Y280575D03*
X629018Y277500D03*
X625684Y273499D03*
X630308Y284500D03*
X632186Y338917D03*
X623500Y379000D03*
X676638Y230894D03*
X658600Y237700D03*
X655600D03*
X681684Y230820D03*
X657259Y263000D03*
X674800Y269600D03*
X660684Y262500D03*
X654100Y263000D03*
X651100Y266000D03*
X679184Y278980D03*
X673684Y280950D03*
X676684D03*
X670184Y288500D03*
X662184Y280500D03*
Y288500D03*
Y284500D03*
X679184Y273190D03*
X676184Y274000D03*
X657500Y330075D03*
X662075Y320000D03*
X675100Y304500D03*
X662125Y308500D03*
X662100Y304500D03*
X658925Y320000D03*
X702223Y197419D03*
X704240Y185000D03*
X689684Y230762D03*
X683592Y259908D03*
X688945Y259761D03*
X695259Y248020D03*
X706984Y261100D03*
X710084D03*
X691794Y261073D03*
X692109Y248020D03*
X686784Y268100D03*
X695584D03*
X698433Y247119D03*
X685884Y297000D03*
X702984Y283500D03*
X706684D03*
X702984Y272400D03*
X706684D03*
X686784Y278000D03*
X695584D03*
X686784Y287900D03*
X695684D03*
X710900Y324100D03*
X696613Y324032D03*
X693904D03*
X691759Y309000D03*
X712000Y215500D03*
X730600Y270000D03*
X727600D03*
X717384Y273400D03*
X719484Y278980D03*
X725000Y292500D03*
X722925Y299500D03*
X719433Y328087D03*
X734500Y307425D03*
X717401Y329996D03*
X770700Y206900D03*
X776000Y206600D03*
X862600Y29500D03*
X867100Y28000D03*
X872533Y29432D03*
X867100Y31500D03*
X887500Y355680D03*
X885100Y361500D03*
X885265Y381000D03*
X878175Y374100D03*
Y364709D03*
X894500Y396500D03*
X954200Y200200D03*
X954600Y207200D03*
X978600Y310955D03*
X1034537Y201437D03*
X1024600Y185000D03*
X1027675Y215000D03*
X1024525D03*
X1034360Y254000D03*
X1032500Y281800D03*
X1029500D03*
X1044900Y278600D03*
X1042800Y273020D03*
X1017300Y322500D03*
X1026270Y303729D03*
X1023492Y346593D03*
X1021414Y355979D03*
X1017300Y385600D03*
X1047163Y197437D03*
X1061600Y228000D03*
X1064600D03*
X1073600D03*
X1070600D03*
X1066600Y264100D03*
X1074430Y256461D03*
X1059300Y268500D03*
X1055600D03*
X1070525Y243000D03*
X1066700Y274000D03*
Y283900D03*
X1052200Y290900D03*
X1055300D03*
X1070490Y290927D03*
X1055600Y279600D03*
X1059300D03*
X1073339Y292239D03*
X1062600Y305000D03*
X1070175Y303980D03*
X1067025D03*
X1072600Y324000D03*
X1064600D03*
X1065800Y339500D03*
X1063300D03*
X1073800D03*
X1071300D03*
X1092100Y263500D03*
X1100100Y243500D03*
X1100500Y263500D03*
X1100100Y247500D03*
X1075500Y264100D03*
X1085600Y271050D03*
X1101500Y271500D03*
X1083100Y273020D03*
X1088079Y274980D03*
X1087100Y282500D03*
X1101600Y289500D03*
X1080600Y294000D03*
X1075500Y274000D03*
Y283900D03*
X1102600Y296000D03*
X1083100Y278810D03*
X1086100Y278000D03*
X1103661Y307700D03*
X1080600Y324000D03*
X1081800Y339500D03*
X1079300D03*
X1086800D03*
X1089300D03*
X1094500Y355600D03*
Y360500D03*
X1129800Y265400D03*
X1131976Y267500D03*
X1108100Y289000D03*
X1121600Y287500D03*
Y283000D03*
X1105025Y289000D03*
X1111100Y291500D03*
Y285000D03*
X1121100Y296000D03*
X1124600Y271425D03*
X1132113Y274500D03*
X1112000Y296000D03*
X1106661Y307700D03*
X1111100Y300500D03*
X1118000Y303500D03*
X1123100Y322500D03*
Y319500D03*
X1130100Y305174D03*
X1130510Y307720D03*
X1123400Y356300D03*
X1132000Y367000D03*
X1145600Y257500D03*
X1149600Y255000D03*
X1160990Y252134D03*
X1146100Y267000D03*
X1157600D03*
X1156200Y258900D03*
X1145600Y244025D03*
X1140100Y244000D03*
X1154025Y247000D03*
X1163266Y255311D03*
X1156584Y292488D03*
X1156509Y295396D03*
X1157600Y276000D03*
X1146100D03*
Y285000D03*
X1157600D03*
X1136000Y278953D03*
X1157800Y312050D03*
X1157138Y303000D03*
X1141600Y312839D03*
X1141500Y347500D03*
X1138500D03*
X1162425Y340500D03*
X1166000Y352500D03*
X1163000D03*
X1153500Y342500D03*
X1187700Y132400D03*
X1197425Y160284D03*
X1187700Y265600D03*
X1171986Y269110D03*
X1173500Y298500D03*
X1196500Y293284D03*
X1171986Y275016D03*
X1176200Y316500D03*
X1173200D03*
X1176000Y350000D03*
X1167800Y355000D03*
X1168200Y349700D03*
X1178900Y359620D03*
X1179500Y350000D03*
Y355000D03*
X1199277Y118477D03*
Y114123D03*
X1210500Y132400D03*
X1199100Y140300D03*
Y133300D03*
Y143800D03*
Y136800D03*
X1200575Y160284D03*
X1199277Y247323D03*
X1210500Y265600D03*
X1199277Y251677D03*
X1199100Y270000D03*
Y266500D03*
X1201500Y293284D03*
X1199100Y277000D03*
Y273500D03*
X1201037Y318912D03*
X1197127Y314264D03*
X1244874Y330000D03*
X1255975D03*
Y337000D03*
X1307700Y78900D03*
Y81900D03*
X1310700D03*
Y78900D03*
X1313700Y81900D03*
Y78900D03*
X1307700Y84900D03*
Y87900D03*
X1310700D03*
Y84900D03*
X1313700Y87900D03*
Y84900D03*
X1307700Y90900D03*
X1310700D03*
X1313700D03*
X1307700Y123300D03*
Y126300D03*
X1310700D03*
Y123300D03*
X1313700Y126300D03*
Y123300D03*
X1307700Y129300D03*
Y132300D03*
Y135300D03*
X1310700D03*
Y132300D03*
Y129300D03*
X1313700Y135300D03*
Y132300D03*
Y129300D03*
Y167700D03*
Y170700D03*
Y173700D03*
Y176700D03*
X1310700Y167700D03*
Y170700D03*
Y173700D03*
Y176700D03*
X1307700D03*
Y173700D03*
Y170700D03*
Y167700D03*
X1313700Y179700D03*
X1310700D03*
X1307700D03*
Y212100D03*
Y215100D03*
X1310700D03*
Y212100D03*
X1313700Y215100D03*
Y212100D03*
X1307700Y218100D03*
Y221100D03*
Y224100D03*
X1310700D03*
Y221100D03*
Y218100D03*
X1313700Y224100D03*
Y221100D03*
Y218100D03*
X1307700Y256500D03*
Y259500D03*
X1310700D03*
Y256500D03*
X1313700Y259500D03*
Y256500D03*
X1307700Y262500D03*
Y265500D03*
Y268500D03*
X1310700D03*
Y265500D03*
Y262500D03*
X1313700Y268500D03*
Y265500D03*
Y262500D03*
X1307700Y300900D03*
Y303900D03*
X1310700D03*
Y300900D03*
X1313700Y303900D03*
Y300900D03*
X1307700Y306900D03*
Y309900D03*
Y312900D03*
X1310700D03*
Y309900D03*
Y306900D03*
X1313700Y309900D03*
Y306900D03*
X1316700Y81900D03*
Y78900D03*
X1319700Y81900D03*
Y78900D03*
X1316700Y87900D03*
Y84900D03*
X1319700Y87900D03*
Y84900D03*
X1320346Y67900D03*
X1316700Y90900D03*
X1319700D03*
X1320346Y112300D03*
X1316700Y126300D03*
Y123300D03*
X1319700Y126300D03*
Y123300D03*
X1316700Y135300D03*
Y132300D03*
Y129300D03*
X1319700Y135300D03*
Y132300D03*
Y129300D03*
X1334140Y146642D03*
X1319700Y167700D03*
Y170700D03*
Y173700D03*
Y176700D03*
X1316700Y167700D03*
Y170700D03*
Y173700D03*
Y176700D03*
X1324100Y150500D03*
X1320346Y156700D03*
X1324100Y194900D03*
X1332671Y190644D03*
X1320346Y201100D03*
X1316700Y215100D03*
Y212100D03*
X1319700Y215100D03*
Y212100D03*
X1316700Y224100D03*
Y221100D03*
Y218100D03*
X1319700Y224100D03*
Y221100D03*
Y218100D03*
X1316700Y259500D03*
Y256500D03*
X1319700Y259500D03*
Y256500D03*
X1316700Y268500D03*
Y265500D03*
Y262500D03*
X1319700Y268500D03*
Y265500D03*
Y262500D03*
X1320346Y245500D03*
Y289900D03*
X1316700Y303900D03*
Y300900D03*
X1319700Y303900D03*
Y300900D03*
X1316700Y306900D03*
X1406230Y21076D03*
Y18076D03*
Y15076D03*
X1403230Y21076D03*
Y18076D03*
Y15076D03*
X1400230Y21076D03*
Y18076D03*
Y15076D03*
X1397230D03*
Y18076D03*
Y21076D03*
X1412230D03*
Y18076D03*
Y15076D03*
X1409230Y21076D03*
Y18076D03*
Y15076D03*
X1498180Y63500D03*
X1494728Y83500D03*
X1490000Y80500D03*
X1499228Y74500D03*
X1494728Y66500D03*
X1490228D03*
X1505100Y64500D03*
X1503728Y74477D03*
X1527100Y98925D03*
X1524600Y111500D03*
X1551000Y96500D03*
X1567500Y67000D03*
X1597100Y145000D03*
Y126000D03*
X1614100Y125000D03*
X1618100Y148925D03*
X1647800Y83200D03*
Y77200D03*
Y80200D03*
X1622295Y114940D03*
X1625370Y103940D03*
X1642037Y104134D03*
X1643537Y101434D03*
X1640037D03*
X1638537Y104134D03*
X1645537D03*
X1647037Y101434D03*
X1632336Y109117D03*
X1631323Y115140D03*
X1624500Y142500D03*
Y146000D03*
X1622295Y118940D03*
X1644917Y124581D03*
X1641932Y122969D03*
X1650117Y180000D03*
X1636600Y173500D03*
X1622100Y155931D03*
X1626000Y163500D03*
Y167500D03*
X1626925Y156000D03*
X1629000Y175000D03*
X1624000Y189000D03*
X1642000Y184500D03*
X1645000D03*
X1660250Y113860D03*
X1657050Y116760D03*
Y113860D03*
X1660250Y116760D03*
X1669800Y120400D03*
X1675800D03*
X1651037Y99734D03*
X1658500Y138000D03*
X1672800Y120400D03*
X1656657Y127365D03*
X1651325Y125076D03*
X1676350Y160251D03*
X1672050Y181550D03*
X1657500Y191500D03*
X1664000Y202500D03*
X1661500Y199000D03*
X1667600Y198500D03*
X1658000Y179500D03*
X1654000Y192500D03*
X1660000Y193500D03*
X1692000Y76570D03*
X1695500Y76500D03*
X1706100Y92000D03*
X1701350Y114250D03*
X1696600Y119000D03*
X1682500Y121825D03*
X1697976Y148000D03*
X1690100Y127375D03*
X1688100Y145560D03*
X1705100Y140500D03*
X1707100Y142500D03*
X1685000Y133000D03*
X1702600Y171500D03*
X1697976Y164500D03*
Y159000D03*
Y175500D03*
Y170000D03*
Y153500D03*
X1680000Y156500D03*
X1688100Y173060D03*
Y162060D03*
X1709600Y158000D03*
X1701000Y159000D03*
Y164500D03*
X1685975Y186500D03*
X1701100Y182000D03*
X1688100Y184220D03*
X1697975Y181000D03*
X1704600Y201500D03*
X1718675Y88000D03*
X1719075Y107016D03*
Y112000D03*
X1718675Y99000D03*
Y93500D03*
X1713524Y109500D03*
Y114500D03*
X1721685Y95940D03*
X1738000Y124500D03*
X1721000Y142525D03*
X1714100Y144925D03*
X1713525Y134500D03*
Y129500D03*
X1713524Y119500D03*
X1727100Y164280D03*
X1715525Y168500D03*
Y153000D03*
X1722063Y156962D03*
X1726099Y153000D03*
X1720524Y175000D03*
X1717600Y158000D03*
X1728475Y175000D03*
X1731925Y199000D03*
X1714175Y187000D03*
X1721500Y205000D03*
X1721600Y194760D03*
Y198500D03*
X1767525Y114016D03*
X1759600Y114500D03*
X1767425Y107000D03*
X1761600Y124524D03*
X1764000Y142525D03*
X1767425Y137000D03*
X1768500Y142525D03*
X1764100Y119500D03*
X1764000Y158025D03*
X1759925Y178900D03*
X1768500Y158025D03*
X1763925Y170984D03*
Y155484D03*
X1766925Y181500D03*
X1769425Y203000D03*
X1754925D03*
X1750563Y198000D03*
X1747925Y204000D03*
X1751600Y258000D03*
Y255500D03*
X1740600Y258000D03*
Y255500D03*
Y248000D03*
Y250500D03*
Y253000D03*
X1751600D03*
Y250500D03*
Y248000D03*
X1766432Y250301D03*
Y247301D03*
X1769300Y329400D03*
Y340600D03*
X1769692Y334649D03*
X1767700Y346200D03*
X1767600Y350000D03*
X1772975Y109500D03*
Y104500D03*
X1773076Y117500D03*
X1773000Y142525D03*
X1773500Y129500D03*
X1772975Y124500D03*
X1773000Y158000D03*
X1772600Y177300D03*
X1800100Y187500D03*
X1778000Y189500D03*
X1789600Y247000D03*
X1783932Y250357D03*
Y247357D03*
X1775432Y250357D03*
Y247357D03*
X1795600Y308000D03*
X1777375Y356300D03*
X1777383Y352305D03*
X1784035Y389535D03*
X1781535D03*
X1784035Y386935D03*
X1781535D03*
X1778838Y389508D03*
Y386908D03*
X1781535Y402935D03*
X1784035D03*
X1778838Y402908D03*
X1781535Y405535D03*
X1784035D03*
X1778838Y405508D03*
X1817500Y188000D03*
X1809600Y195000D03*
X1811500Y186000D03*
X1842164Y419238D03*
X1847164D03*
X1837164D03*
X1852164D03*
X1842164Y432338D03*
X1847164Y430568D03*
X1852164Y435538D03*
X1837164Y428238D03*
G54D20*
X166785Y230000D03*
Y310000D03*
Y390000D03*
Y470000D03*
Y550000D03*
X243785Y230000D03*
Y310000D03*
Y390000D03*
Y470000D03*
Y550000D03*
X1488500Y230000D03*
Y310000D03*
Y390000D03*
Y470000D03*
Y550000D03*
X1565500Y230000D03*
Y310000D03*
Y390000D03*
Y470000D03*
Y550000D03*
G54D47*
X1846142Y270433D03*
X1856772D03*
X1846142Y280433D03*
Y290433D03*
Y300433D03*
X1856772D03*
Y290433D03*
Y280433D03*
X1848957Y324213D03*
X1843957Y329213D03*
X1848957Y314213D03*
X1843957Y319213D03*
X1853957Y329213D03*
Y319213D03*
X1848957Y334213D03*
Y344213D03*
X1843957Y339213D03*
Y349213D03*
X1853957D03*
Y339213D03*
X1858957Y344213D03*
Y334213D03*
G54D15*
X45275Y236614D03*
Y411594D03*
X72835Y236614D03*
X68898Y226771D03*
X59055Y222834D03*
X49212Y226771D03*
X68898Y246457D03*
X49212D03*
X59055Y250394D03*
X68898Y421437D03*
X72835Y411594D03*
X68898Y401751D03*
X59055Y397814D03*
X49212Y401751D03*
Y421437D03*
X59055Y425374D03*
X1673228Y222834D03*
X1663385Y226771D03*
X1659448Y236614D03*
X1663385Y246457D03*
X1673228Y250394D03*
Y397834D03*
X1663385Y401771D03*
X1659448Y411614D03*
X1663385Y421457D03*
X1673228Y425394D03*
X1687008Y236614D03*
X1683071Y226771D03*
Y246457D03*
Y421457D03*
X1687008Y411614D03*
X1683071Y401771D03*
G54D42*
X1642915Y111950D03*
X1639372Y114450D03*
X1646458Y111950D03*
X1642915Y114450D03*
X1639372Y111950D03*
X1646458Y114450D03*
X1650002Y111950D03*
Y114450D03*
G54D28*
X468946Y338216D03*
X465946D03*
X468946Y341216D03*
X465946D03*
X458946Y338216D03*
X455946D03*
X458946Y341216D03*
X455946D03*
Y357216D03*
X458946D03*
X468946Y357016D03*
X465946D03*
X471946Y338216D03*
Y341216D03*
X481446Y338216D03*
X478446D03*
X481446Y341216D03*
X478446D03*
X484446Y338216D03*
Y341216D03*
X471946Y357016D03*
X528084Y77900D03*
Y74900D03*
Y71900D03*
X525084Y77900D03*
Y74900D03*
Y71900D03*
X522084Y77900D03*
Y74900D03*
Y71900D03*
X525084Y116300D03*
X522084D03*
X528084D03*
X525084Y122300D03*
X522084D03*
X525084Y119300D03*
X522084D03*
X528084Y122300D03*
Y119300D03*
X525084Y166700D03*
X522084D03*
X525084Y160700D03*
Y163700D03*
X522084D03*
Y160700D03*
Y205100D03*
Y208100D03*
X525084D03*
Y205100D03*
X522084Y211100D03*
X525084D03*
X522084Y249500D03*
Y252500D03*
X525084D03*
Y249500D03*
X522084Y255500D03*
X525084D03*
X528084Y252500D03*
Y249500D03*
Y255500D03*
Y299900D03*
X525084D03*
X522084D03*
X528084Y296900D03*
X525084D03*
X522084D03*
X528084Y293900D03*
X525084D03*
X522084D03*
X531084Y77900D03*
Y74900D03*
Y71900D03*
Y299900D03*
Y296900D03*
Y293900D03*
X586184Y117800D03*
X583184D03*
X580184D03*
X586184Y114800D03*
X583184D03*
X580184D03*
X586184Y111800D03*
X583184D03*
X580184D03*
X586184Y108800D03*
X583184D03*
X580184D03*
X586184Y105800D03*
X583184D03*
X580184D03*
Y126800D03*
X583184D03*
X586184D03*
Y123800D03*
X583184D03*
X580184D03*
X586184Y120800D03*
X583184D03*
X580184D03*
X583184Y239000D03*
X580184D03*
X583184Y242000D03*
X580184D03*
X583184Y254000D03*
Y251000D03*
Y248000D03*
Y245000D03*
X580184D03*
Y248000D03*
Y251000D03*
Y254000D03*
X583184Y260000D03*
Y257000D03*
X580184D03*
Y260000D03*
X620466Y246839D03*
X664484Y212500D03*
X666984D03*
X672484D03*
X674984D03*
X679484D03*
X681984D03*
X685484D03*
X687984D03*
X1240200Y77900D03*
Y74900D03*
Y71900D03*
Y68900D03*
Y65900D03*
X1237200D03*
Y68900D03*
Y71900D03*
Y74900D03*
Y77900D03*
X1234200Y65900D03*
Y68900D03*
Y71900D03*
Y74900D03*
Y77900D03*
X1231200Y65900D03*
Y68900D03*
Y71900D03*
Y74900D03*
Y77900D03*
X1234200Y116300D03*
Y113300D03*
Y110300D03*
X1237200Y116300D03*
Y113300D03*
Y110300D03*
X1240200D03*
Y113300D03*
Y116300D03*
X1234200Y122300D03*
Y119300D03*
X1237200Y122300D03*
Y119300D03*
X1240200D03*
Y122300D03*
X1237200Y166700D03*
Y163700D03*
Y160700D03*
Y157700D03*
Y154700D03*
X1240200D03*
Y157700D03*
Y160700D03*
Y163700D03*
Y166700D03*
X1237200Y208100D03*
X1240200D03*
X1237200Y211100D03*
X1240200D03*
X1234200Y252500D03*
X1237200D03*
X1234200Y255500D03*
X1237200D03*
X1240200Y252500D03*
Y255500D03*
Y299900D03*
Y296900D03*
X1237200D03*
Y299900D03*
X1234200Y296900D03*
Y299900D03*
X1231200Y296900D03*
Y299900D03*
X1657050Y102380D03*
X1685100Y127500D03*
X1692600Y135975D03*
X1751600Y238000D03*
Y235500D03*
X1740600D03*
Y238000D03*
X1751600Y233000D03*
X1740600D03*
X1766447Y239798D03*
Y242798D03*
X1751600Y240500D03*
X1740600D03*
X1783947Y239798D03*
Y242798D03*
X1775447Y239798D03*
Y242798D03*
X1789600Y243500D03*
G54D29*
X649059Y314000D03*
X1491918Y107773D03*
Y110773D03*
Y113773D03*
Y104773D03*
X1488918D03*
Y113773D03*
Y110773D03*
Y107773D03*
X1485918Y104773D03*
Y113773D03*
Y110773D03*
Y107773D03*
X1482918Y104773D03*
Y113773D03*
Y110773D03*
Y107773D03*
X1618800Y76700D03*
X1615800Y82700D03*
Y79700D03*
Y76700D03*
X1618800Y79700D03*
Y82700D03*
X1727200Y104500D03*
X1728600Y387500D03*
X1731100D03*
X1733600D03*
X1770575Y137000D03*
X1762454Y320347D03*
X1742109Y345235D03*
Y342435D03*
X1747416Y348293D03*
X1747909Y345335D03*
Y342535D03*
X1744909Y345335D03*
Y342535D03*
X1742109Y339635D03*
Y336835D03*
Y334035D03*
X1747909Y339735D03*
Y336935D03*
Y334135D03*
X1744909Y339735D03*
Y336935D03*
Y334135D03*
X1767151Y333311D03*
X1777532Y328322D03*
X1777459Y332322D03*
X1777383Y348288D03*
G54D34*
X802087Y200984D03*
X792087D03*
X822087D03*
X812087D03*
X920197D03*
X910197D03*
X940197D03*
X930197D03*
G54D37*
X825900Y362200D03*
Y372200D03*
X866400Y362200D03*
Y382200D03*
X906900Y362200D03*
Y372200D03*
G54D21*
X163878Y601693D03*
X156004D03*
X163878Y609567D03*
Y617441D03*
Y625315D03*
Y633189D03*
X156004Y609567D03*
Y617441D03*
Y625315D03*
Y633189D03*
X163878Y641063D03*
Y648937D03*
Y656811D03*
X156004Y641063D03*
Y648937D03*
Y656811D03*
X163878Y664685D03*
X156004D03*
X1587107Y601693D03*
Y609567D03*
Y617441D03*
Y625315D03*
Y633189D03*
Y641063D03*
Y648937D03*
Y656811D03*
Y664685D03*
X1594981Y601693D03*
Y609567D03*
Y617441D03*
Y625315D03*
Y633189D03*
Y641063D03*
Y648937D03*
Y656811D03*
Y664685D03*
G54D31*
X681498Y575042D03*
Y565042D03*
X681604Y593187D03*
Y603187D03*
X997833Y575042D03*
Y565042D03*
Y593187D03*
Y603187D03*
G54D43*
X1848583Y99212D03*
X1848582Y481693D03*
G54D18*
X137303Y601693D03*
Y609567D03*
Y617441D03*
Y625315D03*
Y633189D03*
Y641063D03*
Y648937D03*
Y656811D03*
Y664685D03*
X145177Y601693D03*
Y609567D03*
Y617441D03*
Y625315D03*
Y633189D03*
Y641063D03*
Y648937D03*
Y656811D03*
Y664685D03*
X192126Y633189D03*
Y625315D03*
Y617441D03*
X200000Y633189D03*
Y625315D03*
Y617441D03*
X215748Y633189D03*
Y625315D03*
Y617441D03*
X223622Y633189D03*
Y625315D03*
Y617441D03*
X250866Y10197D03*
X255906Y617441D03*
X248032D03*
X255906Y625315D03*
Y633189D03*
X248032D03*
Y625315D03*
X279646Y23012D03*
Y13012D03*
X274646Y18012D03*
X284646Y8012D03*
X274646D03*
X260866Y10197D03*
X279528Y617441D03*
X271654D03*
X279528Y625315D03*
Y633189D03*
X271654D03*
Y625315D03*
X289646Y23012D03*
Y13012D03*
X295276Y617441D03*
Y625315D03*
Y633189D03*
X303150D03*
Y625315D03*
Y617441D03*
X1437008D03*
X1429134D03*
X1437008Y625315D03*
Y633189D03*
X1429134D03*
Y625315D03*
X1465197Y18012D03*
Y8012D03*
X1451417Y10197D03*
X1441417D03*
X1460630Y617441D03*
X1452756D03*
X1460630Y625315D03*
Y633189D03*
X1452756D03*
Y625315D03*
X1480197Y23012D03*
X1470197D03*
X1480197Y13012D03*
X1470197D03*
X1475197Y8012D03*
X1476378Y617441D03*
Y625315D03*
Y633189D03*
X1484252D03*
Y625315D03*
Y617441D03*
X1508661Y633189D03*
Y625315D03*
Y617441D03*
X1516535Y633189D03*
Y625315D03*
Y617441D03*
X1532283Y633189D03*
Y625315D03*
Y617441D03*
X1540157Y633189D03*
Y625315D03*
Y617441D03*
X1576280Y601693D03*
X1568406D03*
X1576280Y609567D03*
Y617441D03*
Y625315D03*
Y633189D03*
X1568406Y609567D03*
Y617441D03*
Y625315D03*
Y633189D03*
X1576280Y641063D03*
Y648937D03*
Y656811D03*
X1568406Y641063D03*
Y648937D03*
Y656811D03*
X1576280Y664685D03*
X1568406D03*
G54D45*
X1846142Y230433D03*
Y240433D03*
X1856772D03*
Y230433D03*
X1846142Y250433D03*
Y260433D03*
X1856772D03*
Y250433D03*
X1858957Y324213D03*
Y314213D03*
G54D38*
X825900Y382200D03*
X906900D03*
G54D41*
X1011017Y598187D03*
G54D40*
Y570042D03*
G54D25*
X207874Y639095D03*
X1524409D03*
G54D14*
X47244Y17716D03*
Y330708D03*
X279528Y53148D03*
X314961Y561023D03*
X393702Y344488D03*
X748032Y64961D03*
Y344488D03*
X984252Y64961D03*
Y344488D03*
X1338584D03*
X1417324Y561023D03*
X1452756Y53149D03*
X1685040Y17716D03*
Y330708D03*
X1799212Y96457D03*
Y478346D03*
G54D27*
X287402Y628465D03*
X263780Y659961D03*
X1468504Y628465D03*
X1444882Y659961D03*
G54D10*
X19685Y-774040D03*
Y766166D03*
X240866Y15512D03*
X300866Y10197D03*
X566575Y463701D03*
D03*
D03*
X1431417Y15512D03*
X1491417Y10197D03*
X1854331Y-774040D03*
Y766166D03*
G54D46*
X1851457Y220433D03*
X1856772Y360433D03*
G54D23*
X231600Y81000D03*
X1212478Y300181D03*
X1529100Y78500D03*
G54D35*
X822087Y88484D03*
Y313484D03*
X940197Y88484D03*
Y313484D03*
G54D22*
X192126Y656811D03*
Y648937D03*
Y664685D03*
X215748Y656811D03*
Y648937D03*
X223622Y656811D03*
Y648937D03*
X200000Y656811D03*
Y648937D03*
X215748Y664685D03*
X223622D03*
X200000D03*
X255906Y648937D03*
X248032D03*
X255906Y656811D03*
X248032D03*
X255906Y664685D03*
X248032D03*
X279528Y648937D03*
X271654D03*
X279528Y656811D03*
X271654D03*
X279528Y664685D03*
X271654D03*
X303150Y648937D03*
X295276D03*
X303150Y656811D03*
X295276D03*
X303150Y664685D03*
X295276D03*
X1437008Y648937D03*
X1429134D03*
X1437008Y656811D03*
X1429134D03*
X1437008Y664685D03*
X1429134D03*
X1460630Y648937D03*
X1452756D03*
X1460630Y656811D03*
X1452756D03*
X1460630Y664685D03*
X1452756D03*
X1484252Y648937D03*
X1476378D03*
X1484252Y656811D03*
X1476378D03*
X1484252Y664685D03*
X1476378D03*
X1508661Y656811D03*
Y648937D03*
X1516535Y656811D03*
Y648937D03*
X1508661Y664685D03*
X1516535D03*
X1532283Y656811D03*
Y648937D03*
X1540157Y656811D03*
Y648937D03*
X1532283Y664685D03*
X1540157D03*
G54D26*
X250866Y20827D03*
X284646Y18012D03*
X260866Y20827D03*
X1451417D03*
X1441417D03*
X1475197Y18012D03*
G54D24*
X225829Y103412D03*
Y99503D03*
X225953Y95780D03*
X225891Y92305D03*
X229829Y103412D03*
X233329D03*
X237329D03*
X229829Y99503D03*
X233329D03*
X237329D03*
X229953Y95780D03*
X233453D03*
X237453D03*
X229891Y92305D03*
X233391D03*
X237391D03*
X622288Y235790D03*
X624788D03*
X1635000Y152925D03*
X1733600Y397500D03*
X1731100D03*
X1728600D03*
G54D11*
X3018Y23930D03*
X10493Y5830D03*
X3018Y43930D03*
Y83930D03*
Y63930D03*
Y103930D03*
Y143930D03*
Y123930D03*
Y163930D03*
Y203930D03*
Y183930D03*
Y223930D03*
Y263930D03*
Y243930D03*
Y283930D03*
Y323930D03*
Y303930D03*
Y343930D03*
Y383930D03*
Y363930D03*
Y403930D03*
Y443930D03*
Y423930D03*
Y463930D03*
Y503930D03*
Y483930D03*
Y523930D03*
Y563930D03*
Y543930D03*
Y583930D03*
X15642Y619715D03*
X3018Y603930D03*
X30709Y3014D03*
X35455Y620194D03*
X75455D03*
X55455D03*
X81406Y3042D03*
X101406D03*
X95455Y620194D03*
X121406Y3042D03*
X137355Y120500D03*
X114923Y623982D03*
X124901Y640105D03*
X161406Y3042D03*
X141406D03*
X154778Y672779D03*
X181406Y3042D03*
X194778Y672779D03*
X174778D03*
X201406Y3042D03*
X221406D03*
X205061Y85500D03*
Y79000D03*
Y75000D03*
Y71500D03*
Y67500D03*
Y89500D03*
Y93000D03*
Y97000D03*
X200600Y109059D03*
X205100Y123000D03*
X214778Y672779D03*
X254778D03*
X234778D03*
X274778D03*
X314766Y39211D03*
X317766D03*
X311956Y651522D03*
X294778Y672779D03*
X323766Y39211D03*
X320766D03*
X324000Y77000D03*
X321000Y63000D03*
X345412Y435017D03*
Y455017D03*
Y475017D03*
Y495017D03*
Y515017D03*
Y535017D03*
Y555017D03*
Y575017D03*
Y595017D03*
X342119Y613510D03*
X331285Y620008D03*
X369192Y38417D03*
X372192D03*
X378192D03*
X375192D03*
X362127Y406608D03*
X350024Y418335D03*
X408100Y180100D03*
Y224500D03*
X399680Y402510D03*
X379680D03*
X419680D03*
X459680D03*
X439680D03*
X498923Y37456D03*
X495923D03*
X492923D03*
X489923D03*
X479680Y402510D03*
X501923Y37456D03*
X504923D03*
X510923D03*
X507923D03*
X528084Y68900D03*
Y65900D03*
X525084Y68900D03*
Y65900D03*
X522084Y68900D03*
Y65900D03*
X525084Y113300D03*
Y110300D03*
X522084Y113300D03*
Y110300D03*
X528084Y113300D03*
Y110300D03*
X525084Y157700D03*
Y154700D03*
X522084Y157700D03*
Y154700D03*
Y199100D03*
Y202100D03*
X525084Y199100D03*
Y202100D03*
X522084Y243500D03*
Y246500D03*
X525084Y243500D03*
Y246500D03*
X528084Y243500D03*
Y246500D03*
Y290900D03*
Y287900D03*
X525084D03*
Y290900D03*
X522084D03*
Y287900D03*
X499680Y402510D03*
X519680D03*
X531084Y68900D03*
Y65900D03*
Y290900D03*
Y287900D03*
X539680Y402510D03*
X559680D03*
X579680D03*
X601675Y305575D03*
X619680Y402510D03*
X599680D03*
X645784Y43500D03*
X648784D03*
X645784Y40500D03*
X648784D03*
X645784Y99000D03*
X648784D03*
X645784Y96000D03*
X648784D03*
X641000Y261500D03*
X639680Y402510D03*
X651784Y43500D03*
Y40500D03*
X657784D03*
X654784D03*
X657784Y43500D03*
X654784D03*
X651784Y99000D03*
Y96000D03*
X657784D03*
X654784D03*
X657784Y99000D03*
X654784D03*
X659000Y284000D03*
X671000Y315760D03*
X668000Y311500D03*
X663500D03*
X657500Y326925D03*
X659680Y402510D03*
X679680D03*
X693863Y189760D03*
X688900Y184260D03*
X704200Y206569D03*
X699680Y402510D03*
X736554Y131056D03*
Y128056D03*
X739554Y131056D03*
Y128056D03*
X742554D03*
X732100Y185000D03*
X729100D03*
X726100D03*
X720100D03*
X723100D03*
X726100Y188000D03*
X729100D03*
X732100D03*
X723100D03*
X720100D03*
X726000Y231500D03*
X729000D03*
X723000D03*
X720000D03*
X732000D03*
Y228500D03*
X720000D03*
X723000D03*
X726000D03*
X729000D03*
X719500Y315500D03*
X734500Y310575D03*
X739680Y402510D03*
X719680D03*
X742554Y131056D03*
X749600Y185000D03*
X752600D03*
X755600D03*
X758600D03*
X746600Y188000D03*
X758600D03*
X755600D03*
X752600D03*
X749600D03*
X746600Y185000D03*
X758500Y231500D03*
X746500D03*
X755500D03*
X752500D03*
X749500D03*
X746500Y228500D03*
X755500D03*
X752500D03*
X749500D03*
X758500D03*
X759680Y402510D03*
X779680D03*
X799680D03*
X819680D03*
X839680D03*
X859680D03*
X880500Y369500D03*
X879680Y402510D03*
X919680D03*
X899680D03*
X939680D03*
X983500Y185000D03*
Y188000D03*
X980500Y185000D03*
X974500D03*
X977500D03*
X980500Y188000D03*
X977500D03*
X974500D03*
Y231500D03*
X977500D03*
X983500D03*
X980500D03*
X983500Y228500D03*
X980500D03*
X977500D03*
X974500D03*
X959680Y402510D03*
X979680D03*
X990954Y131056D03*
Y128056D03*
X993954Y131056D03*
Y128056D03*
X996954D03*
Y131056D03*
X986500Y185000D03*
Y188000D03*
X1004000Y185000D03*
X1001000Y188000D03*
X1004000D03*
X1007000Y185000D03*
X1010000D03*
X1013000D03*
Y188000D03*
X1010000D03*
X1007000D03*
X1001000Y185000D03*
X1004000Y231500D03*
X1007000D03*
X1010000D03*
X1001000D03*
X986500D03*
X1013000D03*
X986500Y228500D03*
X1013000D03*
X1004000D03*
X1007000D03*
X1010000D03*
X1001000D03*
X999680Y402510D03*
X1030100Y207500D03*
X1039680Y402510D03*
X1019680D03*
X1074500Y43500D03*
Y99000D03*
X1059680Y402510D03*
X1077500Y43500D03*
Y40500D03*
X1074500D03*
X1080500D03*
X1083500D03*
X1086500D03*
X1080500Y43500D03*
X1083500D03*
X1086500D03*
X1077500Y99000D03*
Y96000D03*
X1074500D03*
X1080500D03*
X1083500D03*
X1086500D03*
X1080500Y99000D03*
X1083500D03*
X1086500D03*
X1101500Y268500D03*
X1079680Y402510D03*
X1099680D03*
X1118500Y283000D03*
X1106000Y364500D03*
X1112500Y364700D03*
X1122000Y366240D03*
X1119680Y402510D03*
X1155366Y38982D03*
X1152366D03*
X1158366D03*
X1161366D03*
X1143500Y251500D03*
X1141600Y305161D03*
X1154600Y321050D03*
X1143100Y322500D03*
Y320000D03*
X1147000Y342500D03*
X1135000Y366500D03*
X1139000D03*
X1159680Y402510D03*
X1139680D03*
X1176100Y105800D03*
Y108800D03*
X1182100Y105800D03*
Y108800D03*
X1179100D03*
Y105800D03*
X1176100Y111800D03*
Y114800D03*
Y117800D03*
X1182100Y111800D03*
Y114800D03*
Y117800D03*
X1179100D03*
Y114800D03*
Y111800D03*
X1176100Y126800D03*
Y123800D03*
Y120800D03*
X1182100Y126800D03*
Y123800D03*
Y120800D03*
X1179100D03*
Y123800D03*
Y126800D03*
X1176100Y239000D03*
X1171600Y238000D03*
X1179100Y239000D03*
X1182100D03*
X1176100Y254000D03*
Y251000D03*
Y248000D03*
Y245000D03*
Y257000D03*
Y260000D03*
Y242000D03*
X1171600Y241500D03*
X1179100Y242000D03*
Y260000D03*
Y257000D03*
Y245000D03*
Y248000D03*
Y251000D03*
Y254000D03*
X1182100D03*
Y251000D03*
Y248000D03*
Y245000D03*
Y257000D03*
Y260000D03*
Y242000D03*
X1165575Y340500D03*
X1171700Y349900D03*
X1178500Y368740D03*
X1179680Y402510D03*
X1223866Y38482D03*
X1220866D03*
X1225930Y359148D03*
X1199680Y402510D03*
X1219680D03*
X1226866Y38482D03*
X1229866D03*
X1237200Y205100D03*
Y202100D03*
Y199100D03*
X1240200D03*
Y202100D03*
Y205100D03*
X1234200Y249500D03*
Y246500D03*
Y243500D03*
X1237200Y249500D03*
Y246500D03*
Y243500D03*
X1240200D03*
Y246500D03*
Y249500D03*
Y293900D03*
Y290900D03*
Y287900D03*
X1237200D03*
Y290900D03*
Y293900D03*
X1234200Y287900D03*
Y290900D03*
Y293900D03*
X1231200D03*
Y290900D03*
Y287900D03*
X1242930Y359148D03*
Y356148D03*
X1245930Y359148D03*
Y356148D03*
X1248930Y359148D03*
Y356148D03*
X1231930D03*
Y359148D03*
X1228930Y356148D03*
Y359148D03*
X1225930Y356148D03*
X1253930Y379648D03*
X1250930D03*
X1247930D03*
X1239680Y402510D03*
X1264366Y38482D03*
X1261366D03*
X1267366D03*
X1270366D03*
X1260340Y359284D03*
Y356284D03*
X1263340Y359284D03*
Y356284D03*
X1266340Y359284D03*
Y356284D03*
X1286113Y378312D03*
X1265340Y379784D03*
X1268340D03*
X1271340D03*
X1259680Y402510D03*
X1279680D03*
X1313366Y38482D03*
X1307366D03*
X1310366D03*
X1286113Y375312D03*
X1289113Y378312D03*
Y375312D03*
X1292113Y378312D03*
Y375312D03*
Y372312D03*
X1289113D03*
X1299680Y402510D03*
X1316366Y38482D03*
X1339680Y402510D03*
X1319680D03*
X1355310Y38893D03*
X1352310D03*
X1349310D03*
X1358310D03*
X1355100Y160000D03*
X1355000Y204400D03*
X1359620Y402940D03*
X1386882Y434539D03*
Y454539D03*
Y474539D03*
Y494539D03*
Y514539D03*
Y534539D03*
Y554539D03*
Y574539D03*
Y594539D03*
X1389643Y612723D03*
X1403035Y620181D03*
X1422310Y40481D03*
X1419310D03*
X1416310D03*
X1425310D03*
X1420335Y635388D03*
Y655388D03*
X1428754Y670547D03*
X1445829Y672778D03*
X1465829D03*
X1490000Y84000D03*
X1485829Y672778D03*
X1508460Y3003D03*
X1527100Y108500D03*
X1505829Y672778D03*
X1525829D03*
X1548460Y3003D03*
X1528460D03*
X1531600Y96941D03*
X1545829Y672778D03*
X1588460Y3003D03*
X1568460D03*
X1565829Y672778D03*
X1585829D03*
X1608460Y3003D03*
X1609100Y85500D03*
Y82000D03*
X1606100Y85500D03*
Y82000D03*
X1609100Y69500D03*
Y66000D03*
Y62500D03*
X1606100Y69500D03*
Y66000D03*
Y62500D03*
X1602100Y85500D03*
Y82000D03*
Y69500D03*
Y66000D03*
Y62500D03*
X1594930Y115000D03*
X1614100Y110000D03*
Y115000D03*
X1609100Y89000D03*
X1606100D03*
X1602100D03*
X1614100Y120000D03*
Y130000D03*
X1613527Y627220D03*
X1607226Y650448D03*
X1602599Y667628D03*
X1648460Y3003D03*
X1628460D03*
X1629870Y104240D03*
X1647837Y121812D03*
X1638707Y132954D03*
X1623100Y172500D03*
Y178000D03*
X1631585Y188777D03*
X1628658Y620261D03*
X1648675Y620226D03*
X1662000Y106000D03*
X1649197Y132915D03*
X1650990Y122034D03*
X1667000Y138000D03*
X1649500Y173398D03*
X1668075Y189500D03*
X1679176Y194760D03*
X1652600Y212000D03*
X1668675Y620226D03*
X1708460Y3003D03*
X1702525Y129500D03*
X1685976Y148000D03*
Y164500D03*
Y159000D03*
Y153500D03*
Y175500D03*
Y170000D03*
X1701100Y178500D03*
X1685976Y181000D03*
X1702075Y205500D03*
X1688692Y620191D03*
X1708692D03*
X1729255Y25347D03*
Y45347D03*
X1732786Y58461D03*
X1729411Y143661D03*
X1720100Y179500D03*
X1729411Y159161D03*
X1733500Y173760D03*
X1712000Y153000D03*
X1738740Y191500D03*
X1729000Y183500D03*
X1724824Y205276D03*
X1711025Y187000D03*
X1729275Y562751D03*
Y542751D03*
Y582751D03*
Y602751D03*
X1753635Y69037D03*
X1764000Y107000D03*
X1763500Y113000D03*
X1763075Y178900D03*
X1767075Y155484D03*
X1769476Y168500D03*
X1754260Y187260D03*
X1768000D03*
X1746000Y191240D03*
X1751289Y345227D03*
X1747416Y351817D03*
X1747235Y355989D03*
Y359564D03*
Y363689D03*
Y367264D03*
Y371389D03*
Y374964D03*
X1755454Y515746D03*
X1793635Y69037D03*
X1773635D03*
X1773500Y121000D03*
X1772500Y174000D03*
X1770075Y181500D03*
X1776100Y361500D03*
Y371500D03*
Y368500D03*
X1776140Y364405D03*
X1775454Y515746D03*
X1813635Y69037D03*
X1815454Y515746D03*
X1853635Y69037D03*
X1833635D03*
X1844500Y416500D03*
X1847500Y437000D03*
X1835454Y515746D03*
X1855509Y515697D03*
X1871008Y117112D03*
X1871009Y93913D03*
X1871008Y137112D03*
Y177112D03*
Y157112D03*
Y197112D03*
Y237112D03*
Y217112D03*
Y257112D03*
Y297112D03*
Y277112D03*
Y317112D03*
Y357112D03*
Y337112D03*
Y377112D03*
Y417112D03*
Y397112D03*
Y437112D03*
Y477112D03*
Y457112D03*
Y497112D03*
G54D33*
X802087Y145984D03*
X792087D03*
X802087Y135984D03*
X792087D03*
X802087Y180984D03*
X792087D03*
X802087Y170984D03*
X792087D03*
X802087Y230984D03*
X792087D03*
X802087Y220984D03*
X792087D03*
X802087Y265984D03*
X792087D03*
X802087Y255984D03*
X792087D03*
X822087Y145984D03*
X812087D03*
X822087Y135984D03*
X812087D03*
X822087Y180984D03*
X812087D03*
X822087Y170984D03*
X812087D03*
X822087Y230984D03*
X812087D03*
X822087Y220984D03*
X812087D03*
X822087Y265984D03*
X812087D03*
X822087Y255984D03*
X812087D03*
X920197Y145984D03*
X910197D03*
X920197Y135984D03*
X910197D03*
X920197Y180984D03*
X910197D03*
X920197Y170984D03*
X910197D03*
X920197Y230984D03*
X910197D03*
X920197Y220984D03*
X910197D03*
X920197Y265984D03*
X910197D03*
X920197Y255984D03*
X910197D03*
X940197Y145984D03*
X930197D03*
X940197Y135984D03*
X930197D03*
X940197Y180984D03*
X930197D03*
X940197Y170984D03*
X930197D03*
X940197Y230984D03*
X930197D03*
X940197Y220984D03*
X930197D03*
X940197Y265984D03*
X930197D03*
X940197Y255984D03*
X930197D03*
G54D36*
X822087Y88484D03*
Y313484D03*
X940197Y88484D03*
Y313484D03*
G54D16*
X59055Y236614D03*
Y411594D03*
X1673228Y236614D03*
Y411614D03*
G54D44*
X1835739Y99212D03*
X1835738Y481693D03*
G54D12*
X32284Y541339D03*
X59055Y498032D03*
X1673228D03*
X1700000Y541339D03*
G54D39*
X866400Y372200D03*
G54D30*
X668314Y570042D03*
G54D32*
X668420Y598187D03*
%LPC*%
G75*
G54D19*
X166785Y200472D03*
Y280472D03*
Y360472D03*
Y440472D03*
Y520472D03*
X243785Y200472D03*
Y280472D03*
Y360472D03*
Y440472D03*
Y520472D03*
X1488500Y200472D03*
Y280472D03*
Y360472D03*
Y440472D03*
Y520472D03*
X1565500Y200472D03*
Y280472D03*
Y360472D03*
Y440472D03*
Y520472D03*
G54D48*
G01X169956Y197301D02*
X166785Y200472D01*
G01D02*
X163614Y203643D01*
G01X169956D02*
X166785Y200472D01*
G01D02*
X163614Y197301D01*
G01X169956Y277301D02*
X166785Y280472D01*
G01D02*
X163614Y283643D01*
G01X169956D02*
X166785Y280472D01*
G01D02*
X163614Y277301D01*
G01X166785Y360472D02*
X163614Y357301D01*
G01X169956D02*
X166785Y360472D01*
G01D02*
X163614Y363643D01*
G01X169956D02*
X166785Y360472D01*
G01X169956Y437301D02*
X166785Y440472D01*
G01D02*
X163614Y443643D01*
G01X169956D02*
X166785Y440472D01*
G01D02*
X163614Y437301D01*
G01X166785Y520472D02*
X163614Y517301D01*
G01X169956Y523643D02*
X166785Y520472D01*
G01D02*
X163614Y523643D01*
G01X169956Y517301D02*
X166785Y520472D01*
G01X246956Y197301D02*
X243785Y200472D01*
G01D02*
X240614Y203643D01*
G01X246956D02*
X243785Y200472D01*
G01D02*
X240614Y197301D01*
G01X246956Y277301D02*
X243785Y280472D01*
G01D02*
X240614Y283643D01*
G01X246956D02*
X243785Y280472D01*
G01D02*
X240614Y277301D01*
G01X246956Y357301D02*
X243785Y360472D01*
G01D02*
X240614Y363643D01*
G01X246956D02*
X243785Y360472D01*
G01D02*
X240614Y357301D01*
G01X246956Y437301D02*
X243785Y440472D01*
G01D02*
X240614Y443643D01*
G01X246956D02*
X243785Y440472D01*
G01D02*
X240614Y437301D01*
G01X246956Y517301D02*
X243785Y520472D01*
G01D02*
X240614Y523643D01*
G01X246956D02*
X243785Y520472D01*
G01D02*
X240614Y517301D01*
G01X1491671Y197301D02*
X1488500Y200472D01*
G01D02*
X1485329Y203643D01*
G01X1491671D02*
X1488500Y200472D01*
G01D02*
X1485329Y197301D01*
G01X1491671Y277301D02*
X1488500Y280472D01*
G01D02*
X1485329Y283643D01*
G01X1491671D02*
X1488500Y280472D01*
G01D02*
X1485329Y277301D01*
G01X1491671Y357301D02*
X1488500Y360472D01*
G01D02*
X1485329Y363643D01*
G01X1491671D02*
X1488500Y360472D01*
G01D02*
X1485329Y357301D01*
G01X1491671Y437301D02*
X1488500Y440472D01*
G01D02*
X1485329Y443643D01*
G01X1491671D02*
X1488500Y440472D01*
G01D02*
X1485329Y437301D01*
G01X1491671Y517301D02*
X1488500Y520472D01*
G01D02*
X1485329Y523643D01*
G01X1491671D02*
X1488500Y520472D01*
G01D02*
X1485329Y517301D01*
G01X1568671Y197301D02*
X1565500Y200472D01*
G01D02*
X1562329Y203643D01*
G01X1568671D02*
X1565500Y200472D01*
G01D02*
X1562329Y197301D01*
G01X1568671Y277301D02*
X1565500Y280472D01*
G01D02*
X1562329Y283643D01*
G01X1568671D02*
X1565500Y280472D01*
G01D02*
X1562329Y277301D01*
G01X1568671Y357301D02*
X1565500Y360472D01*
G01D02*
X1562329Y363643D01*
G01X1568671D02*
X1565500Y360472D01*
G01D02*
X1562329Y357301D01*
G01X1568671Y437301D02*
X1565500Y440472D01*
G01D02*
X1562329Y443643D01*
G01X1568671D02*
X1565500Y440472D01*
G01D02*
X1562329Y437301D01*
G01X1568671Y517301D02*
X1565500Y520472D01*
G01D02*
X1562329Y523643D01*
G01X1568671D02*
X1565500Y520472D01*
G01D02*
X1562329Y517301D01*
G54D49*
G01X-457143Y-1211429D02*
Y2242857D01*
X4308572D01*
Y-1211429D01*
X-457143D01*
G01X37000Y-995000D02*
Y-1070000D01*
X537000D01*
Y-995000D01*
X37000D01*
G01X49000Y-1060000D02*
Y-1065000D01*
G01X47543Y-1060000D02*
X50457D01*
G01X55367Y-1065000D02*
X52833D01*
Y-1060000D01*
X55367D01*
G01X54353Y-1062417D02*
X52833D01*
G01X57933Y-1060000D02*
Y-1065000D01*
X60467D01*
G01X64300Y-1065167D02*
X64173Y-1065083D01*
Y-1064917D01*
X64300Y-1064833D01*
X64427Y-1064917D01*
Y-1065083D01*
X64300Y-1065167D01*
G01Y-1062917D02*
X64173Y-1062833D01*
Y-1062667D01*
X64300Y-1062583D01*
X64427Y-1062667D01*
Y-1062833D01*
X64300Y-1062917D01*
G01X69083Y-1066667D02*
X68450Y-1065833D01*
X68133Y-1065000D01*
Y-1061667D01*
X68450Y-1060833D01*
X69083Y-1060000D01*
G01X74500D02*
X73993Y-1060167D01*
X73613Y-1060583D01*
X73360Y-1061083D01*
X73170Y-1061750D01*
X73107Y-1062500D01*
X73170Y-1063250D01*
X73360Y-1063917D01*
X73613Y-1064417D01*
X73993Y-1064833D01*
X74500Y-1065000D01*
X75007Y-1064833D01*
X75387Y-1064417D01*
X75640Y-1063917D01*
X75830Y-1063250D01*
X75893Y-1062500D01*
X75830Y-1061750D01*
X75640Y-1061083D01*
X75387Y-1060583D01*
X75007Y-1060167D01*
X74500Y-1060000D01*
G01X78207Y-1064000D02*
X78587Y-1064583D01*
X79093Y-1064917D01*
X79663Y-1065000D01*
X80170Y-1064917D01*
X80677Y-1064500D01*
X80993Y-1064000D01*
X81057Y-1063500D01*
X80930Y-1062917D01*
X80487Y-1062500D01*
X80043Y-1062333D01*
X79473D01*
G01X80043D02*
X80423Y-1062083D01*
X80740Y-1061667D01*
X80867Y-1061167D01*
X80740Y-1060667D01*
X80423Y-1060250D01*
X79853Y-1060000D01*
X79283Y-1060083D01*
X78713Y-1060417D01*
G01X85017Y-1066667D02*
X85650Y-1065833D01*
X85967Y-1065000D01*
Y-1061667D01*
X85650Y-1060833D01*
X85017Y-1060000D01*
G01X88407Y-1064000D02*
X88787Y-1064583D01*
X89293Y-1064917D01*
X89863Y-1065000D01*
X90370Y-1064917D01*
X90877Y-1064500D01*
X91193Y-1064000D01*
X91257Y-1063500D01*
X91130Y-1062917D01*
X90687Y-1062500D01*
X90243Y-1062333D01*
X89673D01*
G01X90243D02*
X90623Y-1062083D01*
X90940Y-1061667D01*
X91067Y-1061167D01*
X90940Y-1060667D01*
X90623Y-1060250D01*
X90053Y-1060000D01*
X89483Y-1060083D01*
X88913Y-1060417D01*
G01X93697Y-1060833D02*
X94077Y-1060333D01*
X94520Y-1060083D01*
X95027Y-1060000D01*
X95660Y-1060167D01*
X96103Y-1060583D01*
X96230Y-1061083D01*
X96167Y-1061583D01*
X95913Y-1062000D01*
X94647Y-1062833D01*
X94077Y-1063417D01*
X93697Y-1064250D01*
X93570Y-1065000D01*
X96230D01*
G01X99873D02*
X100000Y-1063917D01*
X100190Y-1063000D01*
X100443Y-1062167D01*
X100760Y-1061250D01*
X101267Y-1060000D01*
X98733D01*
G01X104277Y-1063333D02*
X105923D01*
G01X108997Y-1060833D02*
X109377Y-1060333D01*
X109820Y-1060083D01*
X110327Y-1060000D01*
X110960Y-1060167D01*
X111403Y-1060583D01*
X111530Y-1061083D01*
X111467Y-1061583D01*
X111213Y-1062000D01*
X109947Y-1062833D01*
X109377Y-1063417D01*
X108997Y-1064250D01*
X108870Y-1065000D01*
X111530D01*
G01X113907Y-1064000D02*
X114287Y-1064583D01*
X114793Y-1064917D01*
X115363Y-1065000D01*
X115870Y-1064917D01*
X116377Y-1064500D01*
X116693Y-1064000D01*
X116757Y-1063500D01*
X116630Y-1062917D01*
X116187Y-1062500D01*
X115743Y-1062333D01*
X115173D01*
G01X115743D02*
X116123Y-1062083D01*
X116440Y-1061667D01*
X116567Y-1061167D01*
X116440Y-1060667D01*
X116123Y-1060250D01*
X115553Y-1060000D01*
X114983Y-1060083D01*
X114413Y-1060417D01*
G01X121160Y-1065000D02*
Y-1060000D01*
X118817Y-1063583D01*
X121983D01*
G01X124107Y-1064250D02*
X124487Y-1064667D01*
X124930Y-1064917D01*
X125500Y-1065000D01*
X126070Y-1064833D01*
X126513Y-1064500D01*
X126830Y-1063917D01*
X126893Y-1063250D01*
X126767Y-1062583D01*
X126450Y-1062167D01*
X126007Y-1061833D01*
X125563Y-1061750D01*
X125120Y-1061833D01*
X124550Y-1062167D01*
X124740Y-1060000D01*
X126450D01*
G01X134497Y-1065000D02*
Y-1060000D01*
X136903D01*
G01X136017Y-1062417D02*
X134497D01*
G01X139217Y-1065000D02*
X140800Y-1060000D01*
X142383Y-1065000D01*
G01X141813Y-1063250D02*
X139787D01*
G01X144570Y-1065000D02*
X147230Y-1060000D01*
G01X144570D02*
X147230Y-1065000D01*
G01X151000Y-1065167D02*
X150873Y-1065083D01*
Y-1064917D01*
X151000Y-1064833D01*
X151127Y-1064917D01*
Y-1065083D01*
X151000Y-1065167D01*
G01Y-1062917D02*
X150873Y-1062833D01*
Y-1062667D01*
X151000Y-1062583D01*
X151127Y-1062667D01*
Y-1062833D01*
X151000Y-1062917D01*
G01X155783Y-1066667D02*
X155150Y-1065833D01*
X154833Y-1065000D01*
Y-1061667D01*
X155150Y-1060833D01*
X155783Y-1060000D01*
G01X161200D02*
X160693Y-1060167D01*
X160313Y-1060583D01*
X160060Y-1061083D01*
X159870Y-1061750D01*
X159807Y-1062500D01*
X159870Y-1063250D01*
X160060Y-1063917D01*
X160313Y-1064417D01*
X160693Y-1064833D01*
X161200Y-1065000D01*
X161707Y-1064833D01*
X162087Y-1064417D01*
X162340Y-1063917D01*
X162530Y-1063250D01*
X162593Y-1062500D01*
X162530Y-1061750D01*
X162340Y-1061083D01*
X162087Y-1060583D01*
X161707Y-1060167D01*
X161200Y-1060000D01*
G01X164907Y-1064000D02*
X165287Y-1064583D01*
X165793Y-1064917D01*
X166363Y-1065000D01*
X166870Y-1064917D01*
X167377Y-1064500D01*
X167693Y-1064000D01*
X167757Y-1063500D01*
X167630Y-1062917D01*
X167187Y-1062500D01*
X166743Y-1062333D01*
X166173D01*
G01X166743D02*
X167123Y-1062083D01*
X167440Y-1061667D01*
X167567Y-1061167D01*
X167440Y-1060667D01*
X167123Y-1060250D01*
X166553Y-1060000D01*
X165983Y-1060083D01*
X165413Y-1060417D01*
G01X171717Y-1066667D02*
X172350Y-1065833D01*
X172667Y-1065000D01*
Y-1061667D01*
X172350Y-1060833D01*
X171717Y-1060000D01*
G01X175107Y-1064000D02*
X175487Y-1064583D01*
X175993Y-1064917D01*
X176563Y-1065000D01*
X177070Y-1064917D01*
X177577Y-1064500D01*
X177893Y-1064000D01*
X177957Y-1063500D01*
X177830Y-1062917D01*
X177387Y-1062500D01*
X176943Y-1062333D01*
X176373D01*
G01X176943D02*
X177323Y-1062083D01*
X177640Y-1061667D01*
X177767Y-1061167D01*
X177640Y-1060667D01*
X177323Y-1060250D01*
X176753Y-1060000D01*
X176183Y-1060083D01*
X175613Y-1060417D01*
G01X180523Y-1064417D02*
X180967Y-1064833D01*
X181473Y-1065000D01*
X181980Y-1064833D01*
X182423Y-1064333D01*
X182740Y-1063583D01*
X182867Y-1062833D01*
Y-1061917D01*
X182740Y-1061167D01*
X182423Y-1060500D01*
X182043Y-1060167D01*
X181600Y-1060000D01*
X181093Y-1060167D01*
X180713Y-1060500D01*
X180460Y-1061000D01*
X180333Y-1061667D01*
X180460Y-1062250D01*
X180777Y-1062833D01*
X181157Y-1063167D01*
X181600Y-1063250D01*
X182107Y-1063083D01*
X182487Y-1062667D01*
X182867Y-1061917D01*
G01X186573Y-1065000D02*
X186700Y-1063917D01*
X186890Y-1063000D01*
X187143Y-1062167D01*
X187460Y-1061250D01*
X187967Y-1060000D01*
X185433D01*
G01X190977Y-1063333D02*
X192623D01*
G01X195507Y-1064000D02*
X195887Y-1064583D01*
X196393Y-1064917D01*
X196963Y-1065000D01*
X197470Y-1064917D01*
X197977Y-1064500D01*
X198293Y-1064000D01*
X198357Y-1063500D01*
X198230Y-1062917D01*
X197787Y-1062500D01*
X197343Y-1062333D01*
X196773D01*
G01X197343D02*
X197723Y-1062083D01*
X198040Y-1061667D01*
X198167Y-1061167D01*
X198040Y-1060667D01*
X197723Y-1060250D01*
X197153Y-1060000D01*
X196583Y-1060083D01*
X196013Y-1060417D01*
G01X200797Y-1062917D02*
X201240Y-1062333D01*
X201620Y-1062000D01*
X202127Y-1061833D01*
X202570Y-1062000D01*
X202887Y-1062333D01*
X203140Y-1062833D01*
X203203Y-1063417D01*
X203140Y-1063917D01*
X202887Y-1064417D01*
X202507Y-1064833D01*
X202063Y-1065000D01*
X201557Y-1064833D01*
X201113Y-1064333D01*
X200860Y-1063583D01*
X200797Y-1062750D01*
X200923Y-1061667D01*
X201113Y-1061083D01*
X201430Y-1060500D01*
X201873Y-1060083D01*
X202317Y-1060000D01*
X202760Y-1060167D01*
X203077Y-1060583D01*
G01X207100Y-1065000D02*
Y-1060000D01*
X206340Y-1061000D01*
G01Y-1065000D02*
X207860D01*
G01X212960D02*
Y-1060000D01*
X210617Y-1063583D01*
X213783D01*
G01X232000Y-995000D02*
Y-1070000D01*
G01Y-1045000D02*
X335000D01*
Y-1020000D01*
G01X232000D02*
X335000D01*
G01X337000Y-995000D02*
Y-1070000D01*
G01X335000Y-995000D02*
Y-1070000D01*
G01X342507Y-1055000D02*
Y-1050000D01*
X343773D01*
X344280Y-1050250D01*
X344660Y-1050583D01*
X344977Y-1051083D01*
X345230Y-1051667D01*
X345293Y-1052500D01*
X345230Y-1053333D01*
X344977Y-1053917D01*
X344660Y-1054417D01*
X344280Y-1054750D01*
X343773Y-1055000D01*
X342507D01*
G01X347417D02*
X349000Y-1050000D01*
X350583Y-1055000D01*
G01X350013Y-1053250D02*
X347987D01*
G01X354100Y-1050000D02*
Y-1055000D01*
G01X352643Y-1050000D02*
X355557D01*
G01X360467Y-1055000D02*
X357933D01*
Y-1050000D01*
X360467D01*
G01X359453Y-1052417D02*
X357933D01*
G01X364300Y-1055167D02*
X364173Y-1055083D01*
Y-1054917D01*
X364300Y-1054833D01*
X364427Y-1054917D01*
Y-1055083D01*
X364300Y-1055167D01*
G01Y-1052917D02*
X364173Y-1052833D01*
Y-1052667D01*
X364300Y-1052583D01*
X364427Y-1052667D01*
Y-1052833D01*
X364300Y-1052917D01*
G01X337000Y-1045000D02*
X537000D01*
G01X342633Y-1030000D02*
Y-1025000D01*
X344153D01*
X344660Y-1025250D01*
X345040Y-1025833D01*
X345167Y-1026500D01*
X345040Y-1027167D01*
X344723Y-1027667D01*
X344153Y-1027917D01*
X342633D01*
G01X347860Y-1030167D02*
X350140Y-1025000D01*
G01X352643Y-1030000D02*
Y-1025000D01*
X355557Y-1030000D01*
Y-1025000D01*
G01X359200Y-1030167D02*
X359073Y-1030083D01*
Y-1029917D01*
X359200Y-1029833D01*
X359327Y-1029917D01*
Y-1030083D01*
X359200Y-1030167D01*
G01Y-1027917D02*
X359073Y-1027833D01*
Y-1027667D01*
X359200Y-1027583D01*
X359327Y-1027667D01*
Y-1027833D01*
X359200Y-1027917D01*
G01X342633Y-1005000D02*
Y-1000000D01*
X344153D01*
X344660Y-1000250D01*
X345040Y-1000833D01*
X345167Y-1001500D01*
X345040Y-1002167D01*
X344723Y-1002667D01*
X344153Y-1002917D01*
X342633D01*
G01X347733Y-1005000D02*
Y-1000000D01*
X349317D01*
X349823Y-1000250D01*
X350140Y-1000583D01*
X350267Y-1001250D01*
X350140Y-1001917D01*
X349760Y-1002333D01*
X349317Y-1002583D01*
X347733D01*
G01X349317D02*
X350267Y-1005000D01*
G01X354100D02*
X353593Y-1004917D01*
X353150Y-1004583D01*
X352770Y-1004083D01*
X352517Y-1003500D01*
X352390Y-1002833D01*
Y-1002167D01*
X352517Y-1001500D01*
X352770Y-1000917D01*
X353150Y-1000417D01*
X353593Y-1000083D01*
X354100Y-1000000D01*
X354607Y-1000083D01*
X355050Y-1000417D01*
X355430Y-1000917D01*
X355683Y-1001500D01*
X355810Y-1002167D01*
Y-1002833D01*
X355683Y-1003500D01*
X355430Y-1004083D01*
X355050Y-1004583D01*
X354607Y-1004917D01*
X354100Y-1005000D01*
G01X357933Y-1004000D02*
X358250Y-1004500D01*
X358630Y-1004833D01*
X359073Y-1005000D01*
X359580Y-1004833D01*
X359960Y-1004500D01*
X360340Y-1004000D01*
X360467Y-1003333D01*
Y-1000000D01*
G01X365567Y-1005000D02*
X363033D01*
Y-1000000D01*
X365567D01*
G01X364553Y-1002417D02*
X363033D01*
G01X370793Y-1000417D02*
X370413Y-1000167D01*
X369970Y-1000000D01*
X369463D01*
X368893Y-1000250D01*
X368450Y-1000667D01*
X368133Y-1001167D01*
X367880Y-1002000D01*
X367817Y-1002750D01*
X367943Y-1003500D01*
X368133Y-1004000D01*
X368513Y-1004500D01*
X368957Y-1004833D01*
X369400Y-1005000D01*
X369843D01*
X370287Y-1004833D01*
X370667Y-1004583D01*
X370983Y-1004250D01*
G01X374500Y-1000000D02*
Y-1005000D01*
G01X373043Y-1000000D02*
X375957D01*
G01X379600Y-1005167D02*
X379473Y-1005083D01*
Y-1004917D01*
X379600Y-1004833D01*
X379727Y-1004917D01*
Y-1005083D01*
X379600Y-1005167D01*
G01Y-1002917D02*
X379473Y-1002833D01*
Y-1002667D01*
X379600Y-1002583D01*
X379727Y-1002667D01*
Y-1002833D01*
X379600Y-1002917D01*
G01X337000Y-1020000D02*
X537000D01*
G01X452000Y-1045000D02*
Y-1070000D01*
G01X454633Y-1047500D02*
Y-1052500D01*
X457167D01*
G01X460240Y-1047500D02*
X461760D01*
G01X461000D02*
Y-1052500D01*
G01X460240D02*
X461760D01*
G01X466607Y-1049833D02*
X466860Y-1049583D01*
X467050Y-1049167D01*
X467177Y-1048583D01*
X467050Y-1048083D01*
X466797Y-1047750D01*
X466353Y-1047500D01*
X464643D01*
Y-1052500D01*
X466733D01*
X467177Y-1052167D01*
X467430Y-1051667D01*
X467557Y-1051083D01*
X467430Y-1050500D01*
X467050Y-1050000D01*
X466607Y-1049833D01*
X464643D01*
G01X471200Y-1052667D02*
X471073Y-1052583D01*
Y-1052417D01*
X471200Y-1052333D01*
X471327Y-1052417D01*
Y-1052583D01*
X471200Y-1052667D01*
G01Y-1050417D02*
X471073Y-1050333D01*
Y-1050167D01*
X471200Y-1050083D01*
X471327Y-1050167D01*
Y-1050333D01*
X471200Y-1050417D01*
G01X495000Y-1045000D02*
Y-1070000D01*
G01X498900Y-1047500D02*
Y-1052500D01*
G01X497443Y-1047500D02*
X500357D01*
G01X504000Y-1052500D02*
X503620Y-1052417D01*
X503240Y-1052083D01*
X502987Y-1051500D01*
X502860Y-1050833D01*
X502987Y-1050167D01*
X503240Y-1049583D01*
X503620Y-1049250D01*
X504000Y-1049167D01*
X504380Y-1049250D01*
X504760Y-1049583D01*
X505013Y-1050167D01*
X505077Y-1050833D01*
X505013Y-1051500D01*
X504760Y-1052083D01*
X504380Y-1052417D01*
X504000Y-1052500D01*
G01X509100D02*
X508720Y-1052417D01*
X508340Y-1052083D01*
X508087Y-1051500D01*
X507960Y-1050833D01*
X508087Y-1050167D01*
X508340Y-1049583D01*
X508720Y-1049250D01*
X509100Y-1049167D01*
X509480Y-1049250D01*
X509860Y-1049583D01*
X510113Y-1050167D01*
X510177Y-1050833D01*
X510113Y-1051500D01*
X509860Y-1052083D01*
X509480Y-1052417D01*
X509100Y-1052500D01*
G01X514200D02*
Y-1047500D01*
G01X519300Y-1052667D02*
X519173Y-1052583D01*
Y-1052417D01*
X519300Y-1052333D01*
X519427Y-1052417D01*
Y-1052583D01*
X519300Y-1052667D01*
G01Y-1050417D02*
X519173Y-1050333D01*
Y-1050167D01*
X519300Y-1050083D01*
X519427Y-1050167D01*
Y-1050333D01*
X519300Y-1050417D01*
G01X495000Y-1020000D02*
Y-1045000D01*
G01X497633Y-1027500D02*
Y-1022500D01*
X499217D01*
X499723Y-1022750D01*
X500040Y-1023083D01*
X500167Y-1023750D01*
X500040Y-1024417D01*
X499660Y-1024833D01*
X499217Y-1025083D01*
X497633D01*
G01X499217D02*
X500167Y-1027500D01*
G01X505267D02*
X502733D01*
Y-1022500D01*
X505267D01*
G01X504253Y-1024917D02*
X502733D01*
G01X507517Y-1022500D02*
X509100Y-1027500D01*
X510683Y-1022500D01*
G01X514200Y-1027667D02*
X514073Y-1027583D01*
Y-1027417D01*
X514200Y-1027333D01*
X514327Y-1027417D01*
Y-1027583D01*
X514200Y-1027667D01*
G01Y-1025417D02*
X514073Y-1025333D01*
Y-1025167D01*
X514200Y-1025083D01*
X514327Y-1025167D01*
Y-1025333D01*
X514200Y-1025417D01*
G01X503013Y-1073167D02*
X503120Y-1073042D01*
X503200Y-1072833D01*
X503253Y-1072542D01*
X503200Y-1072292D01*
X503093Y-1072125D01*
X502907Y-1072000D01*
X502187D01*
Y-1074500D01*
X503067D01*
X503253Y-1074333D01*
X503360Y-1074083D01*
X503413Y-1073792D01*
X503360Y-1073500D01*
X503200Y-1073250D01*
X503013Y-1073167D01*
X502187D01*
G01X505480Y-1074500D02*
Y-1072833D01*
G01Y-1073125D02*
X505373Y-1072958D01*
X505213Y-1072875D01*
X505027Y-1072833D01*
X504840Y-1072917D01*
X504680Y-1073083D01*
X504573Y-1073333D01*
X504520Y-1073667D01*
X504573Y-1074000D01*
X504680Y-1074250D01*
X504840Y-1074417D01*
X505027Y-1074500D01*
X505213Y-1074458D01*
X505373Y-1074333D01*
X505480Y-1074167D01*
G01X506800Y-1074208D02*
X506933Y-1074375D01*
X507120Y-1074500D01*
X507280D01*
X507440Y-1074417D01*
X507547Y-1074292D01*
X507600Y-1074125D01*
X507573Y-1073875D01*
X507467Y-1073750D01*
X506987Y-1073500D01*
X506880Y-1073208D01*
X506933Y-1073000D01*
X507040Y-1072875D01*
X507200Y-1072833D01*
X507360Y-1072875D01*
X507520Y-1073000D01*
G01X509000Y-1073375D02*
X509853D01*
X509773Y-1073083D01*
X509640Y-1072917D01*
X509453Y-1072833D01*
X509267Y-1072875D01*
X509107Y-1073000D01*
X509000Y-1073292D01*
X508947Y-1073542D01*
Y-1073792D01*
X509000Y-1074042D01*
X509133Y-1074292D01*
X509293Y-1074458D01*
X509480Y-1074500D01*
X509667Y-1074417D01*
X509853Y-1074167D01*
G01X511120Y-1074500D02*
Y-1072000D01*
G01Y-1073250D02*
X511253Y-1073000D01*
X511413Y-1072875D01*
X511573Y-1072833D01*
X511813Y-1072917D01*
X511973Y-1073083D01*
X512080Y-1073375D01*
Y-1073708D01*
X512027Y-1074042D01*
X511920Y-1074292D01*
X511733Y-1074458D01*
X511573Y-1074500D01*
X511413Y-1074458D01*
X511253Y-1074333D01*
X511120Y-1074125D01*
G01X513800Y-1074500D02*
X513640Y-1074458D01*
X513480Y-1074292D01*
X513373Y-1074000D01*
X513320Y-1073667D01*
X513373Y-1073333D01*
X513480Y-1073042D01*
X513640Y-1072875D01*
X513800Y-1072833D01*
X513960Y-1072875D01*
X514120Y-1073042D01*
X514227Y-1073333D01*
X514253Y-1073667D01*
X514227Y-1074000D01*
X514120Y-1074292D01*
X513960Y-1074458D01*
X513800Y-1074500D01*
G01X516480D02*
Y-1072833D01*
G01Y-1073125D02*
X516373Y-1072958D01*
X516213Y-1072875D01*
X516027Y-1072833D01*
X515840Y-1072917D01*
X515680Y-1073083D01*
X515573Y-1073333D01*
X515520Y-1073667D01*
X515573Y-1074000D01*
X515680Y-1074250D01*
X515840Y-1074417D01*
X516027Y-1074500D01*
X516213Y-1074458D01*
X516373Y-1074333D01*
X516480Y-1074167D01*
G01X517827Y-1074500D02*
Y-1072833D01*
G01Y-1073167D02*
X517960Y-1073000D01*
X518093Y-1072875D01*
X518280Y-1072833D01*
X518413Y-1072875D01*
X518573Y-1073000D01*
G01X520880Y-1072000D02*
Y-1074500D01*
G01Y-1074125D02*
X520773Y-1074333D01*
X520613Y-1074458D01*
X520427Y-1074500D01*
X520213Y-1074417D01*
X520053Y-1074208D01*
X519947Y-1073958D01*
X519920Y-1073667D01*
X519947Y-1073375D01*
X520053Y-1073125D01*
X520213Y-1072917D01*
X520427Y-1072833D01*
X520613Y-1072875D01*
X520747Y-1072958D01*
X520880Y-1073125D01*
G01X524267Y-1074500D02*
Y-1072000D01*
X524933D01*
X525147Y-1072125D01*
X525280Y-1072292D01*
X525333Y-1072625D01*
X525280Y-1072958D01*
X525120Y-1073167D01*
X524933Y-1073292D01*
X524267D01*
G01X524933D02*
X525333Y-1074500D01*
G01X526600Y-1073375D02*
X527453D01*
X527373Y-1073083D01*
X527240Y-1072917D01*
X527053Y-1072833D01*
X526867Y-1072875D01*
X526707Y-1073000D01*
X526600Y-1073292D01*
X526547Y-1073542D01*
Y-1073792D01*
X526600Y-1074042D01*
X526733Y-1074292D01*
X526893Y-1074458D01*
X527080Y-1074500D01*
X527267Y-1074417D01*
X527453Y-1074167D01*
G01X528720Y-1072833D02*
X529200Y-1074500D01*
X529680Y-1072833D01*
G01X531400Y-1074583D02*
X531347Y-1074542D01*
Y-1074458D01*
X531400Y-1074417D01*
X531453Y-1074458D01*
Y-1074542D01*
X531400Y-1074583D01*
G01X533600Y-1074500D02*
X533787Y-1074458D01*
X534000Y-1074333D01*
X534133Y-1074125D01*
X534187Y-1073833D01*
X534133Y-1073542D01*
X533973Y-1073292D01*
X533733Y-1073167D01*
X533467D01*
X533307Y-1073083D01*
X533173Y-1072875D01*
X533120Y-1072583D01*
X533200Y-1072292D01*
X533387Y-1072083D01*
X533600Y-1072000D01*
X533813Y-1072083D01*
X534000Y-1072292D01*
X534080Y-1072583D01*
X534027Y-1072875D01*
X533893Y-1073083D01*
X533733Y-1073167D01*
X533467D01*
X533227Y-1073292D01*
X533067Y-1073542D01*
X533013Y-1073833D01*
X533067Y-1074125D01*
X533200Y-1074333D01*
X533413Y-1074458D01*
X533600Y-1074500D01*
G01X536013Y-1073167D02*
X536120Y-1073042D01*
X536200Y-1072833D01*
X536253Y-1072542D01*
X536200Y-1072292D01*
X536093Y-1072125D01*
X535907Y-1072000D01*
X535187D01*
Y-1074500D01*
X536067D01*
X536253Y-1074333D01*
X536360Y-1074083D01*
X536413Y-1073792D01*
X536360Y-1073500D01*
X536200Y-1073250D01*
X536013Y-1073167D01*
X535187D01*
G01X-457143Y-1211429D02*
Y2242857D01*
X4308572D01*
Y-1211429D01*
X-457143D01*
G01X71650Y-1024800D02*
X69130Y-1024383D01*
X66925Y-1022717D01*
X65035Y-1020217D01*
X63775Y-1017300D01*
X63145Y-1013967D01*
Y-1010633D01*
X63775Y-1007300D01*
X65035Y-1004383D01*
X66925Y-1001884D01*
X69130Y-1000217D01*
X71650Y-999800D01*
X74170Y-1000217D01*
X76375Y-1001884D01*
X78265Y-1004383D01*
X79525Y-1007300D01*
X80155Y-1010633D01*
Y-1013967D01*
X79525Y-1017300D01*
X78265Y-1020217D01*
X76375Y-1022717D01*
X74170Y-1024383D01*
X71650Y-1024800D01*
G01X74170Y-1018133D02*
X77950Y-1024800D01*
G01X91495Y-1008134D02*
Y-1019800D01*
X92755Y-1022717D01*
X94645Y-1024383D01*
X96850Y-1024800D01*
X99055Y-1024383D01*
X100945Y-1022717D01*
X102205Y-1019800D01*
G01Y-1024800D02*
Y-1008134D01*
G01X127720Y-1024800D02*
Y-1008134D01*
G01Y-1011050D02*
X126460Y-1009384D01*
X124570Y-1008550D01*
X122365Y-1008134D01*
X120160Y-1008967D01*
X118270Y-1010633D01*
X117010Y-1013134D01*
X116380Y-1016467D01*
X117010Y-1019800D01*
X118270Y-1022301D01*
X120160Y-1023967D01*
X122365Y-1024800D01*
X124570Y-1024383D01*
X126460Y-1023134D01*
X127720Y-1021467D01*
G01X141895Y-1024800D02*
Y-1008134D01*
G01Y-1012300D02*
X143155Y-1010217D01*
X145045Y-1008550D01*
X147565Y-1008134D01*
X149770Y-1008550D01*
X151660Y-1010217D01*
X152605Y-1013134D01*
Y-1024800D01*
G01X172450Y-999800D02*
Y-1024800D01*
G01X168040Y-1008134D02*
X176860D01*
G01X203320Y-1024800D02*
Y-1008134D01*
G01Y-1011050D02*
X202060Y-1009384D01*
X200170Y-1008550D01*
X197965Y-1008134D01*
X195760Y-1008967D01*
X193870Y-1010633D01*
X192610Y-1013134D01*
X191980Y-1016467D01*
X192610Y-1019800D01*
X193870Y-1022301D01*
X195760Y-1023967D01*
X197965Y-1024800D01*
X200170Y-1024383D01*
X202060Y-1023134D01*
X203320Y-1021467D01*
G01X49820Y-1042350D02*
X51387D01*
Y-1044240D01*
X50917Y-1044870D01*
X50368Y-1045290D01*
X49585Y-1045500D01*
X48802Y-1045290D01*
X48253Y-1044870D01*
X47783Y-1044240D01*
X47470Y-1043505D01*
X47313Y-1042665D01*
Y-1041930D01*
X47470Y-1041300D01*
X47783Y-1040565D01*
X48253Y-1039935D01*
X48723Y-1039515D01*
X49350Y-1039200D01*
X49898D01*
X50525Y-1039410D01*
X50995Y-1039830D01*
G01X53927Y-1039200D02*
Y-1043715D01*
X54240Y-1044660D01*
X54867Y-1045290D01*
X55650Y-1045500D01*
X56433Y-1045290D01*
X57060Y-1044660D01*
X57373Y-1043715D01*
Y-1039200D01*
G01X61010D02*
X62890D01*
G01X61950D02*
Y-1045500D01*
G01X61010D02*
X62890D01*
G01X66605Y-1044660D02*
X67232Y-1045185D01*
X67937Y-1045500D01*
X68563D01*
X69190Y-1045185D01*
X69660Y-1044660D01*
X69895Y-1043925D01*
X69738Y-1043190D01*
X69347Y-1042560D01*
X68642Y-1042140D01*
X67702Y-1041930D01*
X67153Y-1041510D01*
X66918Y-1040775D01*
X67075Y-1040040D01*
X67467Y-1039515D01*
X68015Y-1039200D01*
X68563D01*
X69112Y-1039410D01*
X69582Y-1039935D01*
G01X72905Y-1045500D02*
Y-1039200D01*
G01X76195D02*
Y-1045500D01*
G01Y-1042350D02*
X72905D01*
G01X78892Y-1045500D02*
X80850Y-1039200D01*
X82808Y-1045500D01*
G01X82103Y-1043295D02*
X79597D01*
G01X85348Y-1045500D02*
Y-1039200D01*
X88952Y-1045500D01*
Y-1039200D01*
G01X98027Y-1045500D02*
Y-1039200D01*
X99593D01*
X100220Y-1039515D01*
X100690Y-1039935D01*
X101082Y-1040565D01*
X101395Y-1041300D01*
X101473Y-1042350D01*
X101395Y-1043400D01*
X101082Y-1044135D01*
X100690Y-1044765D01*
X100220Y-1045185D01*
X99593Y-1045500D01*
X98027D01*
G01X105110Y-1039200D02*
X106990D01*
G01X106050D02*
Y-1045500D01*
G01X105110D02*
X106990D01*
G01X110705Y-1044660D02*
X111332Y-1045185D01*
X112037Y-1045500D01*
X112663D01*
X113290Y-1045185D01*
X113760Y-1044660D01*
X113995Y-1043925D01*
X113838Y-1043190D01*
X113447Y-1042560D01*
X112742Y-1042140D01*
X111802Y-1041930D01*
X111253Y-1041510D01*
X111018Y-1040775D01*
X111175Y-1040040D01*
X111567Y-1039515D01*
X112115Y-1039200D01*
X112663D01*
X113212Y-1039410D01*
X113682Y-1039935D01*
G01X118650Y-1039200D02*
Y-1045500D01*
G01X116848Y-1039200D02*
X120452D01*
G01X124950Y-1045710D02*
X124793Y-1045605D01*
Y-1045395D01*
X124950Y-1045290D01*
X125107Y-1045395D01*
Y-1045605D01*
X124950Y-1045710D01*
G01X131093Y-1046655D02*
X131407Y-1045290D01*
G01X137550Y-1039200D02*
Y-1045500D01*
G01X135748Y-1039200D02*
X139352D01*
G01X141892Y-1045500D02*
X143850Y-1039200D01*
X145808Y-1045500D01*
G01X145103Y-1043295D02*
X142597D01*
G01X150150Y-1045500D02*
X149523Y-1045395D01*
X148975Y-1044975D01*
X148505Y-1044345D01*
X148192Y-1043610D01*
X148035Y-1042770D01*
Y-1041930D01*
X148192Y-1041090D01*
X148505Y-1040355D01*
X148975Y-1039725D01*
X149523Y-1039305D01*
X150150Y-1039200D01*
X150777Y-1039305D01*
X151325Y-1039725D01*
X151795Y-1040355D01*
X152108Y-1041090D01*
X152265Y-1041930D01*
Y-1042770D01*
X152108Y-1043610D01*
X151795Y-1044345D01*
X151325Y-1044975D01*
X150777Y-1045395D01*
X150150Y-1045500D01*
G01X156450D02*
Y-1042665D01*
X154883Y-1039200D01*
G01X158017D02*
X156450Y-1042665D01*
G01X161027Y-1039200D02*
Y-1043715D01*
X161340Y-1044660D01*
X161967Y-1045290D01*
X162750Y-1045500D01*
X163533Y-1045290D01*
X164160Y-1044660D01*
X164473Y-1043715D01*
Y-1039200D01*
G01X167092Y-1045500D02*
X169050Y-1039200D01*
X171008Y-1045500D01*
G01X170303Y-1043295D02*
X167797D01*
G01X173548Y-1045500D02*
Y-1039200D01*
X177152Y-1045500D01*
Y-1039200D01*
G01X51073Y-1049725D02*
X50603Y-1049410D01*
X50055Y-1049200D01*
X49428D01*
X48723Y-1049515D01*
X48175Y-1050040D01*
X47783Y-1050670D01*
X47470Y-1051720D01*
X47392Y-1052665D01*
X47548Y-1053610D01*
X47783Y-1054240D01*
X48253Y-1054870D01*
X48802Y-1055290D01*
X49350Y-1055500D01*
X49898D01*
X50447Y-1055290D01*
X50917Y-1054975D01*
X51308Y-1054555D01*
G01X54710Y-1049200D02*
X56590D01*
G01X55650D02*
Y-1055500D01*
G01X54710D02*
X56590D01*
G01X61950Y-1049200D02*
Y-1055500D01*
G01X60148Y-1049200D02*
X63752D01*
G01X68250Y-1055500D02*
Y-1052665D01*
X66683Y-1049200D01*
G01X69817D02*
X68250Y-1052665D01*
G01X79127Y-1054240D02*
X79597Y-1054975D01*
X80223Y-1055395D01*
X80928Y-1055500D01*
X81555Y-1055395D01*
X82182Y-1054870D01*
X82573Y-1054240D01*
X82652Y-1053610D01*
X82495Y-1052875D01*
X81947Y-1052350D01*
X81398Y-1052140D01*
X80693D01*
G01X81398D02*
X81868Y-1051825D01*
X82260Y-1051300D01*
X82417Y-1050670D01*
X82260Y-1050040D01*
X81868Y-1049515D01*
X81163Y-1049200D01*
X80458Y-1049305D01*
X79753Y-1049725D01*
G01X85427Y-1054240D02*
X85897Y-1054975D01*
X86523Y-1055395D01*
X87228Y-1055500D01*
X87855Y-1055395D01*
X88482Y-1054870D01*
X88873Y-1054240D01*
X88952Y-1053610D01*
X88795Y-1052875D01*
X88247Y-1052350D01*
X87698Y-1052140D01*
X86993D01*
G01X87698D02*
X88168Y-1051825D01*
X88560Y-1051300D01*
X88717Y-1050670D01*
X88560Y-1050040D01*
X88168Y-1049515D01*
X87463Y-1049200D01*
X86758Y-1049305D01*
X86053Y-1049725D01*
G01X91727Y-1054240D02*
X92197Y-1054975D01*
X92823Y-1055395D01*
X93528Y-1055500D01*
X94155Y-1055395D01*
X94782Y-1054870D01*
X95173Y-1054240D01*
X95252Y-1053610D01*
X95095Y-1052875D01*
X94547Y-1052350D01*
X93998Y-1052140D01*
X93293D01*
G01X93998D02*
X94468Y-1051825D01*
X94860Y-1051300D01*
X95017Y-1050670D01*
X94860Y-1050040D01*
X94468Y-1049515D01*
X93763Y-1049200D01*
X93058Y-1049305D01*
X92353Y-1049725D01*
G01X99593Y-1055500D02*
X99750Y-1054135D01*
X99985Y-1052980D01*
X100298Y-1051930D01*
X100690Y-1050775D01*
X101317Y-1049200D01*
X98183D01*
G01X105893Y-1055500D02*
X106050Y-1054135D01*
X106285Y-1052980D01*
X106598Y-1051930D01*
X106990Y-1050775D01*
X107617Y-1049200D01*
X104483D01*
G01X112193Y-1056655D02*
X112507Y-1055290D01*
G01X118650Y-1049200D02*
Y-1055500D01*
G01X116848Y-1049200D02*
X120452D01*
G01X122992Y-1055500D02*
X124950Y-1049200D01*
X126908Y-1055500D01*
G01X126203Y-1053295D02*
X123697D01*
G01X130310Y-1049200D02*
X132190D01*
G01X131250D02*
Y-1055500D01*
G01X130310D02*
X132190D01*
G01X135200Y-1049200D02*
X136297Y-1055500D01*
X137550Y-1049200D01*
X138803Y-1055500D01*
X139900Y-1049200D01*
G01X141892Y-1055500D02*
X143850Y-1049200D01*
X145808Y-1055500D01*
G01X145103Y-1053295D02*
X142597D01*
G01X148348Y-1055500D02*
Y-1049200D01*
X151952Y-1055500D01*
Y-1049200D01*
G01X162358Y-1057600D02*
X161575Y-1056550D01*
X161183Y-1055500D01*
Y-1051300D01*
X161575Y-1050250D01*
X162358Y-1049200D01*
G01X173783Y-1055500D02*
Y-1049200D01*
X175742D01*
X176368Y-1049515D01*
X176760Y-1049935D01*
X176917Y-1050775D01*
X176760Y-1051615D01*
X176290Y-1052140D01*
X175742Y-1052455D01*
X173783D01*
G01X175742D02*
X176917Y-1055500D01*
G01X181650Y-1055710D02*
X181493Y-1055605D01*
Y-1055395D01*
X181650Y-1055290D01*
X181807Y-1055395D01*
Y-1055605D01*
X181650Y-1055710D01*
G01X187950Y-1055500D02*
X187323Y-1055395D01*
X186775Y-1054975D01*
X186305Y-1054345D01*
X185992Y-1053610D01*
X185835Y-1052770D01*
Y-1051930D01*
X185992Y-1051090D01*
X186305Y-1050355D01*
X186775Y-1049725D01*
X187323Y-1049305D01*
X187950Y-1049200D01*
X188577Y-1049305D01*
X189125Y-1049725D01*
X189595Y-1050355D01*
X189908Y-1051090D01*
X190065Y-1051930D01*
Y-1052770D01*
X189908Y-1053610D01*
X189595Y-1054345D01*
X189125Y-1054975D01*
X188577Y-1055395D01*
X187950Y-1055500D01*
G01X194250Y-1055710D02*
X194093Y-1055605D01*
Y-1055395D01*
X194250Y-1055290D01*
X194407Y-1055395D01*
Y-1055605D01*
X194250Y-1055710D01*
G01X202273Y-1049725D02*
X201803Y-1049410D01*
X201255Y-1049200D01*
X200628D01*
X199923Y-1049515D01*
X199375Y-1050040D01*
X198983Y-1050670D01*
X198670Y-1051720D01*
X198592Y-1052665D01*
X198748Y-1053610D01*
X198983Y-1054240D01*
X199453Y-1054870D01*
X200002Y-1055290D01*
X200550Y-1055500D01*
X201098D01*
X201647Y-1055290D01*
X202117Y-1054975D01*
X202508Y-1054555D01*
G01X206850Y-1055710D02*
X206693Y-1055605D01*
Y-1055395D01*
X206850Y-1055290D01*
X207007Y-1055395D01*
Y-1055605D01*
X206850Y-1055710D01*
G01X213542Y-1057600D02*
X214325Y-1056550D01*
X214717Y-1055500D01*
Y-1051300D01*
X214325Y-1050250D01*
X213542Y-1049200D01*
G01X47548Y-1035500D02*
Y-1029200D01*
X51152Y-1035500D01*
Y-1029200D01*
G01X55650Y-1035500D02*
X55023Y-1035395D01*
X54475Y-1034975D01*
X54005Y-1034345D01*
X53692Y-1033610D01*
X53535Y-1032770D01*
Y-1031930D01*
X53692Y-1031090D01*
X54005Y-1030355D01*
X54475Y-1029725D01*
X55023Y-1029305D01*
X55650Y-1029200D01*
X56277Y-1029305D01*
X56825Y-1029725D01*
X57295Y-1030355D01*
X57608Y-1031090D01*
X57765Y-1031930D01*
Y-1032770D01*
X57608Y-1033610D01*
X57295Y-1034345D01*
X56825Y-1034975D01*
X56277Y-1035395D01*
X55650Y-1035500D01*
G01X61950Y-1035710D02*
X61793Y-1035605D01*
Y-1035395D01*
X61950Y-1035290D01*
X62107Y-1035395D01*
Y-1035605D01*
X61950Y-1035710D01*
G01X66762Y-1030250D02*
X67232Y-1029620D01*
X67780Y-1029305D01*
X68407Y-1029200D01*
X69190Y-1029410D01*
X69738Y-1029935D01*
X69895Y-1030565D01*
X69817Y-1031195D01*
X69503Y-1031720D01*
X67937Y-1032770D01*
X67232Y-1033505D01*
X66762Y-1034555D01*
X66605Y-1035500D01*
X69895D01*
G01X74550D02*
Y-1029200D01*
X73610Y-1030460D01*
G01Y-1035500D02*
X75490D01*
G01X80850D02*
Y-1029200D01*
X79910Y-1030460D01*
G01Y-1035500D02*
X81790D01*
G01X86993Y-1036655D02*
X87307Y-1035290D01*
G01X91100Y-1029200D02*
X92197Y-1035500D01*
X93450Y-1029200D01*
X94703Y-1035500D01*
X95800Y-1029200D01*
G01X101317Y-1035500D02*
X98183D01*
Y-1029200D01*
X101317D01*
G01X100063Y-1032245D02*
X98183D01*
G01X104248Y-1035500D02*
Y-1029200D01*
X107852Y-1035500D01*
Y-1029200D01*
G01X110705Y-1035500D02*
Y-1029200D01*
G01X113995D02*
Y-1035500D01*
G01Y-1032350D02*
X110705D01*
G01X116927Y-1029200D02*
Y-1033715D01*
X117240Y-1034660D01*
X117867Y-1035290D01*
X118650Y-1035500D01*
X119433Y-1035290D01*
X120060Y-1034660D01*
X120373Y-1033715D01*
Y-1029200D01*
G01X122992Y-1035500D02*
X124950Y-1029200D01*
X126908Y-1035500D01*
G01X126203Y-1033295D02*
X123697D01*
G01X136062Y-1030250D02*
X136532Y-1029620D01*
X137080Y-1029305D01*
X137707Y-1029200D01*
X138490Y-1029410D01*
X139038Y-1029935D01*
X139195Y-1030565D01*
X139117Y-1031195D01*
X138803Y-1031720D01*
X137237Y-1032770D01*
X136532Y-1033505D01*
X136062Y-1034555D01*
X135905Y-1035500D01*
X139195D01*
G01X142048D02*
Y-1029200D01*
X145652Y-1035500D01*
Y-1029200D01*
G01X148427Y-1035500D02*
Y-1029200D01*
X149993D01*
X150620Y-1029515D01*
X151090Y-1029935D01*
X151482Y-1030565D01*
X151795Y-1031300D01*
X151873Y-1032350D01*
X151795Y-1033400D01*
X151482Y-1034135D01*
X151090Y-1034765D01*
X150620Y-1035185D01*
X149993Y-1035500D01*
X148427D01*
G01X161183D02*
Y-1029200D01*
X163142D01*
X163768Y-1029515D01*
X164160Y-1029935D01*
X164317Y-1030775D01*
X164160Y-1031615D01*
X163690Y-1032140D01*
X163142Y-1032455D01*
X161183D01*
G01X163142D02*
X164317Y-1035500D01*
G01X167327D02*
Y-1029200D01*
X168893D01*
X169520Y-1029515D01*
X169990Y-1029935D01*
X170382Y-1030565D01*
X170695Y-1031300D01*
X170773Y-1032350D01*
X170695Y-1033400D01*
X170382Y-1034135D01*
X169990Y-1034765D01*
X169520Y-1035185D01*
X168893Y-1035500D01*
X167327D01*
G01X175350Y-1035710D02*
X175193Y-1035605D01*
Y-1035395D01*
X175350Y-1035290D01*
X175507Y-1035395D01*
Y-1035605D01*
X175350Y-1035710D01*
G01X243000Y-1004500D02*
Y-1012500D01*
X247000D01*
G01X254800D02*
Y-1007167D01*
G01Y-1008100D02*
X254400Y-1007567D01*
X253800Y-1007300D01*
X253100Y-1007167D01*
X252400Y-1007433D01*
X251800Y-1007967D01*
X251400Y-1008767D01*
X251200Y-1009833D01*
X251400Y-1010900D01*
X251800Y-1011700D01*
X252400Y-1012233D01*
X253100Y-1012500D01*
X253800Y-1012367D01*
X254400Y-1011967D01*
X254800Y-1011434D01*
G01X258900Y-1014900D02*
X259500Y-1015167D01*
X260300Y-1014900D01*
X260800Y-1014367D01*
X261200Y-1013700D01*
X261800Y-1011567D01*
X263100Y-1007167D01*
G01X259900D02*
X261800Y-1011567D01*
G01X267500Y-1008900D02*
X270700D01*
X270400Y-1007967D01*
X269900Y-1007433D01*
X269200Y-1007167D01*
X268500Y-1007300D01*
X267900Y-1007700D01*
X267500Y-1008633D01*
X267300Y-1009434D01*
Y-1010233D01*
X267500Y-1011033D01*
X268000Y-1011833D01*
X268600Y-1012367D01*
X269300Y-1012500D01*
X270000Y-1012233D01*
X270700Y-1011434D01*
G01X275600Y-1012500D02*
Y-1007167D01*
G01Y-1008233D02*
X276100Y-1007700D01*
X276600Y-1007300D01*
X277300Y-1007167D01*
X277800Y-1007300D01*
X278400Y-1007700D01*
G01X262100Y-1054500D02*
X265900D01*
X262100Y-1062500D01*
X265900D01*
G01X272000Y-1057167D02*
Y-1062500D01*
G01Y-1055033D02*
X271800Y-1054900D01*
Y-1054633D01*
X272000Y-1054500D01*
X272200Y-1054633D01*
Y-1054900D01*
X272000Y-1055033D01*
G01X278700Y-1059833D02*
X281300D01*
G01X286200Y-1065167D02*
Y-1057167D01*
G01Y-1058367D02*
X286700Y-1057700D01*
X287200Y-1057300D01*
X288000Y-1057167D01*
X288700Y-1057300D01*
X289400Y-1057967D01*
X289700Y-1058900D01*
X289800Y-1059833D01*
X289700Y-1060767D01*
X289400Y-1061700D01*
X288800Y-1062233D01*
X288000Y-1062500D01*
X287300Y-1062367D01*
X286600Y-1061967D01*
X286200Y-1061434D01*
G01X296000Y-1057167D02*
Y-1062500D01*
G01Y-1055033D02*
X295800Y-1054900D01*
Y-1054633D01*
X296000Y-1054500D01*
X296200Y-1054633D01*
Y-1054900D01*
X296000Y-1055033D01*
G01X302300Y-1062500D02*
Y-1057167D01*
G01Y-1058500D02*
X302700Y-1057833D01*
X303300Y-1057300D01*
X304100Y-1057167D01*
X304800Y-1057300D01*
X305400Y-1057833D01*
X305700Y-1058767D01*
Y-1062500D01*
G01X310600Y-1064500D02*
X311300Y-1065033D01*
X312100Y-1065167D01*
X312800Y-1065033D01*
X313400Y-1064367D01*
X313800Y-1063433D01*
Y-1057167D01*
G01Y-1058233D02*
X313400Y-1057700D01*
X312800Y-1057300D01*
X312100Y-1057167D01*
X311300Y-1057433D01*
X310800Y-1057967D01*
X310400Y-1058900D01*
X310200Y-1059833D01*
X310300Y-1060633D01*
X310700Y-1061567D01*
X311300Y-1062233D01*
X312100Y-1062500D01*
X312700Y-1062367D01*
X313400Y-1061833D01*
X313800Y-1061300D01*
G01X277100Y-1033500D02*
X279100D01*
Y-1035900D01*
X278500Y-1036700D01*
X277800Y-1037233D01*
X276800Y-1037500D01*
X275800Y-1037233D01*
X275100Y-1036700D01*
X274500Y-1035900D01*
X274100Y-1034967D01*
X273900Y-1033900D01*
Y-1032967D01*
X274100Y-1032167D01*
X274500Y-1031233D01*
X275100Y-1030433D01*
X275700Y-1029900D01*
X276500Y-1029500D01*
X277200D01*
X278000Y-1029767D01*
X278600Y-1030300D01*
G01X282200Y-1037500D02*
Y-1029500D01*
X286800Y-1037500D01*
Y-1029500D01*
G01X290300Y-1037500D02*
Y-1029500D01*
X292300D01*
X293100Y-1029900D01*
X293700Y-1030433D01*
X294200Y-1031233D01*
X294600Y-1032167D01*
X294700Y-1033500D01*
X294600Y-1034833D01*
X294200Y-1035767D01*
X293700Y-1036567D01*
X293100Y-1037100D01*
X292300Y-1037500D01*
X290300D01*
G01X300500D02*
Y-1029500D01*
X299300Y-1031100D01*
G01Y-1037500D02*
X301700D01*
G01X297700Y-1012500D02*
Y-1004500D01*
X294000Y-1010233D01*
X299000D01*
G01X369600Y-1055833D02*
X370200Y-1055033D01*
X370900Y-1054633D01*
X371700Y-1054500D01*
X372700Y-1054767D01*
X373400Y-1055433D01*
X373600Y-1056233D01*
X373500Y-1057034D01*
X373100Y-1057700D01*
X371100Y-1059033D01*
X370200Y-1059967D01*
X369600Y-1061300D01*
X369400Y-1062500D01*
X373600D01*
G01X379500Y-1054500D02*
X378700Y-1054767D01*
X378100Y-1055433D01*
X377700Y-1056233D01*
X377400Y-1057300D01*
X377300Y-1058500D01*
X377400Y-1059700D01*
X377700Y-1060767D01*
X378100Y-1061567D01*
X378700Y-1062233D01*
X379500Y-1062500D01*
X380300Y-1062233D01*
X380900Y-1061567D01*
X381300Y-1060767D01*
X381600Y-1059700D01*
X381700Y-1058500D01*
X381600Y-1057300D01*
X381300Y-1056233D01*
X380900Y-1055433D01*
X380300Y-1054767D01*
X379500Y-1054500D01*
G01X385600Y-1055833D02*
X386200Y-1055033D01*
X386900Y-1054633D01*
X387700Y-1054500D01*
X388700Y-1054767D01*
X389400Y-1055433D01*
X389600Y-1056233D01*
X389500Y-1057034D01*
X389100Y-1057700D01*
X387100Y-1059033D01*
X386200Y-1059967D01*
X385600Y-1061300D01*
X385400Y-1062500D01*
X389600D01*
G01X393600Y-1055833D02*
X394200Y-1055033D01*
X394900Y-1054633D01*
X395700Y-1054500D01*
X396700Y-1054767D01*
X397400Y-1055433D01*
X397600Y-1056233D01*
X397500Y-1057034D01*
X397100Y-1057700D01*
X395100Y-1059033D01*
X394200Y-1059967D01*
X393600Y-1061300D01*
X393400Y-1062500D01*
X397600D01*
G01X401700Y-1062767D02*
X405300Y-1054500D01*
G01X411500Y-1062500D02*
Y-1054500D01*
X410300Y-1056100D01*
G01Y-1062500D02*
X412700D01*
G01X417600Y-1055833D02*
X418200Y-1055033D01*
X418900Y-1054633D01*
X419700Y-1054500D01*
X420700Y-1054767D01*
X421400Y-1055433D01*
X421600Y-1056233D01*
X421500Y-1057034D01*
X421100Y-1057700D01*
X419100Y-1059033D01*
X418200Y-1059967D01*
X417600Y-1061300D01*
X417400Y-1062500D01*
X421600D01*
G01X425700Y-1062767D02*
X429300Y-1054500D01*
G01X435500Y-1062500D02*
Y-1054500D01*
X434300Y-1056100D01*
G01Y-1062500D02*
X436700D01*
G01X441300Y-1060900D02*
X441900Y-1061833D01*
X442700Y-1062367D01*
X443600Y-1062500D01*
X444400Y-1062367D01*
X445200Y-1061700D01*
X445700Y-1060900D01*
X445800Y-1060100D01*
X445600Y-1059167D01*
X444900Y-1058500D01*
X444200Y-1058233D01*
X443300D01*
G01X444200D02*
X444800Y-1057833D01*
X445300Y-1057167D01*
X445500Y-1056367D01*
X445300Y-1055567D01*
X444800Y-1054900D01*
X443900Y-1054500D01*
X443000Y-1054633D01*
X442100Y-1055167D01*
G01X369300Y-1040000D02*
Y-1032000D01*
X371300D01*
X372100Y-1032400D01*
X372700Y-1032933D01*
X373200Y-1033733D01*
X373600Y-1034667D01*
X373700Y-1036000D01*
X373600Y-1037333D01*
X373200Y-1038267D01*
X372700Y-1039067D01*
X372100Y-1039600D01*
X371300Y-1040000D01*
X369300D01*
G01X377000D02*
X379500Y-1032000D01*
X382000Y-1040000D01*
G01X381100Y-1037200D02*
X377900D01*
G01X385600Y-1040000D02*
Y-1032000D01*
X389400D01*
G01X388000Y-1035867D02*
X385600D01*
G01X395500Y-1032000D02*
X394700Y-1032267D01*
X394100Y-1032933D01*
X393700Y-1033733D01*
X393400Y-1034800D01*
X393300Y-1036000D01*
X393400Y-1037200D01*
X393700Y-1038267D01*
X394100Y-1039067D01*
X394700Y-1039733D01*
X395500Y-1040000D01*
X396300Y-1039733D01*
X396900Y-1039067D01*
X397300Y-1038267D01*
X397600Y-1037200D01*
X397700Y-1036000D01*
X397600Y-1034800D01*
X397300Y-1033733D01*
X396900Y-1032933D01*
X396300Y-1032267D01*
X395500Y-1032000D01*
G01X403500D02*
Y-1040000D01*
G01X401200Y-1032000D02*
X405800D01*
G01X409500Y-1040000D02*
Y-1032000D01*
X411900D01*
X412700Y-1032400D01*
X413300Y-1033333D01*
X413500Y-1034400D01*
X413300Y-1035467D01*
X412800Y-1036267D01*
X411900Y-1036667D01*
X409500D01*
G01X420300Y-1035733D02*
X420700Y-1035333D01*
X421000Y-1034667D01*
X421200Y-1033733D01*
X421000Y-1032933D01*
X420600Y-1032400D01*
X419900Y-1032000D01*
X417200D01*
Y-1040000D01*
X420500D01*
X421200Y-1039467D01*
X421600Y-1038667D01*
X421800Y-1037733D01*
X421600Y-1036800D01*
X421000Y-1036000D01*
X420300Y-1035733D01*
X417200D01*
G01X427500Y-1040000D02*
Y-1032000D01*
X426300Y-1033600D01*
G01Y-1040000D02*
X428700D01*
G01X433000D02*
X435500Y-1032000D01*
X438000Y-1040000D01*
G01X437100Y-1037200D02*
X433900D01*
G01X441600Y-1040000D02*
Y-1032000D01*
X445400D01*
G01X444000Y-1035867D02*
X441600D01*
G01X451500Y-1032000D02*
X450700Y-1032267D01*
X450100Y-1032933D01*
X449700Y-1033733D01*
X449400Y-1034800D01*
X449300Y-1036000D01*
X449400Y-1037200D01*
X449700Y-1038267D01*
X450100Y-1039067D01*
X450700Y-1039733D01*
X451500Y-1040000D01*
X452300Y-1039733D01*
X452900Y-1039067D01*
X453300Y-1038267D01*
X453600Y-1037200D01*
X453700Y-1036000D01*
X453600Y-1034800D01*
X453300Y-1033733D01*
X452900Y-1032933D01*
X452300Y-1032267D01*
X451500Y-1032000D01*
G01X389600Y-1012500D02*
Y-1004500D01*
X393400D01*
G01X392000Y-1008367D02*
X389600D01*
G01X399500Y-1004500D02*
X398700Y-1004767D01*
X398100Y-1005433D01*
X397700Y-1006233D01*
X397400Y-1007300D01*
X397300Y-1008500D01*
X397400Y-1009700D01*
X397700Y-1010767D01*
X398100Y-1011567D01*
X398700Y-1012233D01*
X399500Y-1012500D01*
X400300Y-1012233D01*
X400900Y-1011567D01*
X401300Y-1010767D01*
X401600Y-1009700D01*
X401700Y-1008500D01*
X401600Y-1007300D01*
X401300Y-1006233D01*
X400900Y-1005433D01*
X400300Y-1004767D01*
X399500Y-1004500D01*
G01X407500D02*
Y-1012500D01*
G01X405200Y-1004500D02*
X409800D01*
G01X412500Y-1015167D02*
X418500D01*
G01X421500Y-1012500D02*
Y-1004500D01*
X423900D01*
X424700Y-1004900D01*
X425300Y-1005833D01*
X425500Y-1006900D01*
X425300Y-1007967D01*
X424800Y-1008767D01*
X423900Y-1009167D01*
X421500D01*
G01X429300Y-1012500D02*
Y-1004500D01*
X431300D01*
X432100Y-1004900D01*
X432700Y-1005433D01*
X433200Y-1006233D01*
X433600Y-1007167D01*
X433700Y-1008500D01*
X433600Y-1009833D01*
X433200Y-1010767D01*
X432700Y-1011567D01*
X432100Y-1012100D01*
X431300Y-1012500D01*
X429300D01*
G01X440300Y-1008233D02*
X440700Y-1007833D01*
X441000Y-1007167D01*
X441200Y-1006233D01*
X441000Y-1005433D01*
X440600Y-1004900D01*
X439900Y-1004500D01*
X437200D01*
Y-1012500D01*
X440500D01*
X441200Y-1011967D01*
X441600Y-1011167D01*
X441800Y-1010233D01*
X441600Y-1009300D01*
X441000Y-1008500D01*
X440300Y-1008233D01*
X437200D01*
G01X444500Y-1015167D02*
X450500D01*
G01X456300Y-1008233D02*
X456700Y-1007833D01*
X457000Y-1007167D01*
X457200Y-1006233D01*
X457000Y-1005433D01*
X456600Y-1004900D01*
X455900Y-1004500D01*
X453200D01*
Y-1012500D01*
X456500D01*
X457200Y-1011967D01*
X457600Y-1011167D01*
X457800Y-1010233D01*
X457600Y-1009300D01*
X457000Y-1008500D01*
X456300Y-1008233D01*
X453200D01*
G01X461300Y-1012500D02*
Y-1004500D01*
X463300D01*
X464100Y-1004900D01*
X464700Y-1005433D01*
X465200Y-1006233D01*
X465600Y-1007167D01*
X465700Y-1008500D01*
X465600Y-1009833D01*
X465200Y-1010767D01*
X464700Y-1011567D01*
X464100Y-1012100D01*
X463300Y-1012500D01*
X461300D01*
G01X468500Y-1015167D02*
X474500D01*
G01X480100Y-1008500D02*
X482100D01*
Y-1010900D01*
X481500Y-1011700D01*
X480800Y-1012233D01*
X479800Y-1012500D01*
X478800Y-1012233D01*
X478100Y-1011700D01*
X477500Y-1010900D01*
X477100Y-1009967D01*
X476900Y-1008900D01*
Y-1007967D01*
X477100Y-1007167D01*
X477500Y-1006233D01*
X478100Y-1005433D01*
X478700Y-1004900D01*
X479500Y-1004500D01*
X480200D01*
X481000Y-1004767D01*
X481600Y-1005300D01*
G01X485500Y-1012500D02*
Y-1004500D01*
X487900D01*
X488700Y-1004900D01*
X489300Y-1005833D01*
X489500Y-1006900D01*
X489300Y-1007967D01*
X488800Y-1008767D01*
X487900Y-1009167D01*
X485500D01*
G01X493300Y-1004500D02*
Y-1010233D01*
X493700Y-1011434D01*
X494500Y-1012233D01*
X495500Y-1012500D01*
X496500Y-1012233D01*
X497300Y-1011434D01*
X497700Y-1010233D01*
Y-1004500D01*
G01X458000Y-1065500D02*
Y-1057500D01*
X456800Y-1059100D01*
G01Y-1065500D02*
X459200D01*
G01X464100Y-1062167D02*
X464800Y-1061233D01*
X465400Y-1060700D01*
X466200Y-1060433D01*
X466900Y-1060700D01*
X467400Y-1061233D01*
X467800Y-1062033D01*
X467900Y-1062967D01*
X467800Y-1063767D01*
X467400Y-1064567D01*
X466800Y-1065233D01*
X466100Y-1065500D01*
X465300Y-1065233D01*
X464600Y-1064434D01*
X464200Y-1063233D01*
X464100Y-1061900D01*
X464300Y-1060167D01*
X464600Y-1059233D01*
X465100Y-1058300D01*
X465800Y-1057633D01*
X466500Y-1057500D01*
X467200Y-1057767D01*
X467700Y-1058433D01*
G01X474000Y-1065767D02*
X473800Y-1065633D01*
Y-1065367D01*
X474000Y-1065233D01*
X474200Y-1065367D01*
Y-1065633D01*
X474000Y-1065767D01*
G01X480100Y-1062167D02*
X480800Y-1061233D01*
X481400Y-1060700D01*
X482200Y-1060433D01*
X482900Y-1060700D01*
X483400Y-1061233D01*
X483800Y-1062033D01*
X483900Y-1062967D01*
X483800Y-1063767D01*
X483400Y-1064567D01*
X482800Y-1065233D01*
X482100Y-1065500D01*
X481300Y-1065233D01*
X480600Y-1064434D01*
X480200Y-1063233D01*
X480100Y-1061900D01*
X480300Y-1060167D01*
X480600Y-1059233D01*
X481100Y-1058300D01*
X481800Y-1057633D01*
X482500Y-1057500D01*
X483200Y-1057767D01*
X483700Y-1058433D01*
G01X503000Y-1065500D02*
Y-1057500D01*
X501800Y-1059100D01*
G01Y-1065500D02*
X504200D01*
G01X510800D02*
X511000Y-1063767D01*
X511300Y-1062300D01*
X511700Y-1060967D01*
X512200Y-1059500D01*
X513000Y-1057500D01*
X509000D01*
G01X519000Y-1065767D02*
X518800Y-1065633D01*
Y-1065367D01*
X519000Y-1065233D01*
X519200Y-1065367D01*
Y-1065633D01*
X519000Y-1065767D01*
G01X525100Y-1058833D02*
X525700Y-1058033D01*
X526400Y-1057633D01*
X527200Y-1057500D01*
X528200Y-1057767D01*
X528900Y-1058433D01*
X529100Y-1059233D01*
X529000Y-1060034D01*
X528600Y-1060700D01*
X526600Y-1062033D01*
X525700Y-1062967D01*
X525100Y-1064300D01*
X524900Y-1065500D01*
X529100D01*
G01X523100Y-1040500D02*
Y-1032500D01*
X526900D01*
G01X525500Y-1036367D02*
X523100D01*
M02*
